FILE_TYPE = MACRO_DRAWING;
SET COLOR_WIRE YELLOW;
SET COLOR_PROP ORANGE;
SET COLOR_DOT WHITE;
SET COLOR_ARC YELLOW;
SET COLOR_BODY GREEN;
SET COLOR_NOTE PURPLE;
SET PROP_DISPLAY VALUE;
SET PAGE_NUMBER P87;
FORCEADD GND..1
(-2300 2300);
FORCEPROP 3 LASTPIN (-2300 2350) SIG_NAME GND\g
J 0
(-2290 2360);
DISPLAY 0.659574 (-2290 2360);
PAINT MONO (-2290 2360);
DISPLAY INVISIBLE (-2290 2360);
FORCEPROP 1 LAST SIZE 1B
J 0
(-2225 2250);
DISPLAY 0.851064 (-2225 2250);
PAINT GREEN (-2225 2250);
DISPLAY INVISIBLE (-2225 2250);
FORCEPROP 2 LAST CDS_LIB mstr_symbols
J 0
(-2300 2300);
DISPLAY 0.723404 (-2300 2300);
DISPLAY INVISIBLE (-2300 2300);
FORCEPROP 1 LAST VOLTAGE 0.0
J 0
(-2345 2257);
DISPLAY 0.723404 (-2345 2257);
PAINT SKYBLUE (-2345 2257);
DISPLAY INVISIBLE (-2345 2257);
FORCEPROP 1 LAST BODY_TYPE PLUMBING
J 0
(-2345 2257);
DISPLAY 0.340426 (-2345 2257);
PAINT GREEN (-2345 2257);
DISPLAY INVISIBLE (-2345 2257);
FORCEPROP 1 LAST HDL_POWER GND
J 0
(-2300 2450);
DISPLAY 0.851064 (-2300 2450);
PAINT GREEN (-2300 2450);
DISPLAY INVISIBLE (-2300 2450);
FORCEPROP 1 LAST PATH I150
J 0
(-2225 2300);
DISPLAY 0.872340 (-2225 2300);
PAINT GREEN (-2225 2300);
DISPLAY INVISIBLE (-2225 2300);
FORCEADD GND..1
(-500 2100);
FORCEPROP 3 LASTPIN (-500 2150) SIG_NAME GND\g
J 0
(-490 2160);
DISPLAY 0.659574 (-490 2160);
PAINT MONO (-490 2160);
DISPLAY INVISIBLE (-490 2160);
FORCEPROP 2 LAST CDS_LIB mstr_symbols
J 0
(-500 2100);
DISPLAY 0.723404 (-500 2100);
DISPLAY INVISIBLE (-500 2100);
FORCEPROP 1 LAST SIZE 1B
J 0
(-425 2050);
DISPLAY 0.851064 (-425 2050);
PAINT GREEN (-425 2050);
DISPLAY INVISIBLE (-425 2050);
FORCEPROP 1 LAST VOLTAGE 0.0
J 0
(-545 2057);
DISPLAY 0.723404 (-545 2057);
PAINT SKYBLUE (-545 2057);
DISPLAY INVISIBLE (-545 2057);
FORCEPROP 1 LAST BODY_TYPE PLUMBING
J 0
(-545 2057);
DISPLAY 0.340426 (-545 2057);
PAINT GREEN (-545 2057);
DISPLAY INVISIBLE (-545 2057);
FORCEPROP 1 LAST HDL_POWER GND
J 0
(-500 2250);
DISPLAY 0.851064 (-500 2250);
PAINT GREEN (-500 2250);
DISPLAY INVISIBLE (-500 2250);
FORCEPROP 1 LAST PATH I152
J 0
(-425 2100);
DISPLAY 0.872340 (-425 2100);
PAINT GREEN (-425 2100);
DISPLAY INVISIBLE (-425 2100);
FORCEADD OFFPAGE..5
(-8525 2275);
FORCEPROP 2 LAST $XR0 12 
J 0
(-8779 2275);
DISPLAY 0.638298 (-8779 2275);
PAINT MONO (-8779 2275);
FORCEPROP 2 LAST CDS_LIB mstr_standard
J 0
(-8525 2275);
DISPLAY 0.808511 (-8525 2275);
DISPLAY INVISIBLE (-8525 2275);
FORCEPROP 1 LAST OFFPAGE TRUE
J 0
(-8200 2150);
DISPLAY 0.872340 (-8200 2150);
PAINT GREEN (-8200 2150);
DISPLAY INVISIBLE (-8200 2150);
FORCEPROP 1 LAST COMMENT_BODY TRUE
J 0
(-8425 2200);
DISPLAY 0.872340 (-8425 2200);
PAINT GREEN (-8425 2200);
DISPLAY INVISIBLE (-8425 2200);
FORCEPROP 2 LAST PATH I167
J 0
(-8475 2350);
DISPLAY 0.808511 (-8475 2350);
DISPLAY INVISIBLE (-8475 2350);
FORCEADD OFFPAGE..5
(-8525 2325);
FORCEPROP 2 LAST $XR0 12 
J 0
(-8779 2325);
DISPLAY 0.638298 (-8779 2325);
PAINT MONO (-8779 2325);
FORCEPROP 2 LAST CDS_LIB mstr_standard
J 0
(-8525 2325);
DISPLAY 0.808511 (-8525 2325);
DISPLAY INVISIBLE (-8525 2325);
FORCEPROP 1 LAST OFFPAGE TRUE
J 0
(-8200 2200);
DISPLAY 0.872340 (-8200 2200);
PAINT GREEN (-8200 2200);
DISPLAY INVISIBLE (-8200 2200);
FORCEPROP 1 LAST COMMENT_BODY TRUE
J 0
(-8425 2250);
DISPLAY 0.872340 (-8425 2250);
PAINT GREEN (-8425 2250);
DISPLAY INVISIBLE (-8425 2250);
FORCEPROP 2 LAST PATH I168
J 0
(-8475 2400);
DISPLAY 0.808511 (-8475 2400);
DISPLAY INVISIBLE (-8475 2400);
FORCEADD OFFPAGE..6
(-8525 3925);
FORCEPROP 2 LAST $XR0 12 
J 0
(-8774 3925);
DISPLAY 0.638298 (-8774 3925);
PAINT MONO (-8774 3925);
FORCEPROP 2 LAST CDS_LIB mstr_standard
J 0
(-8525 3925);
DISPLAY 0.723404 (-8525 3925);
PAINT MONO (-8525 3925);
DISPLAY INVISIBLE (-8525 3925);
FORCEPROP 1 LAST OFFPAGE TRUE
J 0
(-8200 3800);
DISPLAY 0.872340 (-8200 3800);
PAINT GREEN (-8200 3800);
DISPLAY INVISIBLE (-8200 3800);
FORCEPROP 1 LAST COMMENT_BODY TRUE
J 0
(-8425 3850);
DISPLAY 0.872340 (-8425 3850);
PAINT GREEN (-8425 3850);
DISPLAY INVISIBLE (-8425 3850);
FORCEPROP 2 LAST PATH I174
J 0
(-8475 4000);
DISPLAY 0.808511 (-8475 4000);
DISPLAY INVISIBLE (-8475 4000);
FORCEADD OFFPAGE..1
(-8525 3425);
FORCEPROP 2 LAST $XR0 12 
J 0
(-8746 3425);
DISPLAY 0.638298 (-8746 3425);
PAINT MONO (-8746 3425);
FORCEPROP 2 LAST CDS_LIB mstr_standard
J 0
(-8525 3425);
DISPLAY 0.808511 (-8525 3425);
DISPLAY INVISIBLE (-8525 3425);
FORCEPROP 1 LAST OFFPAGE TRUE
J 0
(-8200 3300);
DISPLAY 0.872340 (-8200 3300);
PAINT GREEN (-8200 3300);
DISPLAY INVISIBLE (-8200 3300);
FORCEPROP 1 LAST COMMENT_BODY TRUE
J 0
(-8400 3325);
DISPLAY 0.872340 (-8400 3325);
PAINT GREEN (-8400 3325);
DISPLAY INVISIBLE (-8400 3325);
FORCEPROP 2 LAST PATH I176
J 0
(-8725 3650);
DISPLAY 0.808511 (-8725 3650);
DISPLAY INVISIBLE (-8725 3650);
FORCEADD VCC_CORE..1
(-8800 3775);
FORCEPROP 3 LASTPIN (-8800 3725) SIG_NAME P3V3_AUX\g
J 0
(-8790 3735);
DISPLAY 0.659574 (-8790 3735);
PAINT MONO (-8790 3735);
DISPLAY INVISIBLE (-8790 3735);
FORCEPROP 1 LAST HDL_POWER P3V3_AUX
J 1
(-8800 3825);
DISPLAY 0.489362 (-8800 3825);
PAINT GREEN (-8800 3825);
FORCEPROP 2 LAST CDS_LIB mstr_symbols
J 0
(-8800 3775);
PAINT MONO (-8800 3775);
DISPLAY INVISIBLE (-8800 3775);
FORCEPROP 0 LAST VOLTAGE 3.3
J 0
(-9075 3925);
DISPLAY 1.021277 (-9075 3925);
PAINT SKYBLUE (-9075 3925);
DISPLAY INVISIBLE (-9075 3925);
FORCEPROP 2 LAST ROOM PVCCINFAON_CPU0_CTRL
J 0
(-8800 3875);
DISPLAY 0.808511 (-8800 3875);
PAINT RED (-8800 3875);
DISPLAY INVISIBLE (-8800 3875);
FORCEPROP 1 LAST PATH I177
J 0
(-8750 3800);
DISPLAY 0.872340 (-8750 3800);
PAINT GREEN (-8750 3800);
DISPLAY INVISIBLE (-8750 3800);
FORCEADD OFFPAGE..1
(-8525 4425);
FORCEPROP 2 LAST $XR0 12 
J 0
(-8746 4425);
DISPLAY 0.638298 (-8746 4425);
PAINT MONO (-8746 4425);
FORCEPROP 2 LAST CDS_LIB mstr_standard
J 0
(-8525 4425);
DISPLAY 0.808511 (-8525 4425);
DISPLAY INVISIBLE (-8525 4425);
FORCEPROP 1 LAST OFFPAGE TRUE
J 0
(-8200 4300);
DISPLAY 0.872340 (-8200 4300);
PAINT GREEN (-8200 4300);
DISPLAY INVISIBLE (-8200 4300);
FORCEPROP 1 LAST COMMENT_BODY TRUE
J 0
(-8400 4325);
DISPLAY 0.872340 (-8400 4325);
PAINT GREEN (-8400 4325);
DISPLAY INVISIBLE (-8400 4325);
FORCEPROP 2 LAST PATH I178
J 0
(-8475 4500);
DISPLAY 0.808511 (-8475 4500);
DISPLAY INVISIBLE (-8475 4500);
FORCEADD OFFPAGE..6
(-8525 4375);
FORCEPROP 2 LAST $XR0 12 
J 0
(-8774 4375);
DISPLAY 0.638298 (-8774 4375);
PAINT MONO (-8774 4375);
FORCEPROP 2 LAST CDS_LIB mstr_standard
J 0
(-8525 4375);
DISPLAY 0.723404 (-8525 4375);
PAINT MONO (-8525 4375);
DISPLAY INVISIBLE (-8525 4375);
FORCEPROP 1 LAST OFFPAGE TRUE
J 0
(-8200 4250);
DISPLAY 0.872340 (-8200 4250);
PAINT GREEN (-8200 4250);
DISPLAY INVISIBLE (-8200 4250);
FORCEPROP 1 LAST COMMENT_BODY TRUE
J 0
(-8425 4300);
DISPLAY 0.872340 (-8425 4300);
PAINT GREEN (-8425 4300);
DISPLAY INVISIBLE (-8425 4300);
FORCEPROP 2 LAST PATH I179
J 0
(-8475 4450);
DISPLAY 0.808511 (-8475 4450);
DISPLAY INVISIBLE (-8475 4450);
FORCEADD OFFPAGE..1
(-8525 4475);
FORCEPROP 2 LAST $XR0 12 
J 0
(-8746 4475);
DISPLAY 0.638298 (-8746 4475);
PAINT MONO (-8746 4475);
FORCEPROP 2 LAST CDS_LIB mstr_standard
J 0
(-8525 4475);
DISPLAY 0.723404 (-8525 4475);
PAINT MONO (-8525 4475);
DISPLAY INVISIBLE (-8525 4475);
FORCEPROP 1 LAST OFFPAGE TRUE
J 0
(-8200 4350);
DISPLAY 0.872340 (-8200 4350);
PAINT GREEN (-8200 4350);
DISPLAY INVISIBLE (-8200 4350);
FORCEPROP 1 LAST COMMENT_BODY TRUE
J 0
(-8400 4375);
DISPLAY 0.872340 (-8400 4375);
PAINT GREEN (-8400 4375);
DISPLAY INVISIBLE (-8400 4375);
FORCEPROP 2 LAST PATH I180
J 0
(-8475 4550);
DISPLAY 0.808511 (-8475 4550);
DISPLAY INVISIBLE (-8475 4550);
FORCEADD OFFPAGE..1
(-8525 4575);
FORCEPROP 2 LAST $XR0 12 
J 0
(-8746 4575);
DISPLAY 0.638298 (-8746 4575);
PAINT MONO (-8746 4575);
FORCEPROP 2 LAST CDS_LIB mstr_standard
J 0
(-8525 4575);
DISPLAY 0.808511 (-8525 4575);
DISPLAY INVISIBLE (-8525 4575);
FORCEPROP 1 LAST OFFPAGE TRUE
J 0
(-8200 4450);
DISPLAY 0.872340 (-8200 4450);
PAINT GREEN (-8200 4450);
DISPLAY INVISIBLE (-8200 4450);
FORCEPROP 1 LAST COMMENT_BODY TRUE
J 0
(-8400 4475);
DISPLAY 0.872340 (-8400 4475);
PAINT GREEN (-8400 4475);
DISPLAY INVISIBLE (-8400 4475);
FORCEPROP 2 LAST PATH I181
J 0
(-8475 4650);
DISPLAY 0.808511 (-8475 4650);
DISPLAY INVISIBLE (-8475 4650);
FORCEADD OFFPAGE..1
(-8525 4625);
FORCEPROP 2 LAST $XR0 12 
J 0
(-8746 4625);
DISPLAY 0.638298 (-8746 4625);
PAINT MONO (-8746 4625);
FORCEPROP 2 LAST CDS_LIB mstr_standard
J 0
(-8525 4625);
DISPLAY 0.723404 (-8525 4625);
PAINT MONO (-8525 4625);
DISPLAY INVISIBLE (-8525 4625);
FORCEPROP 1 LAST OFFPAGE TRUE
J 0
(-8200 4500);
DISPLAY 0.872340 (-8200 4500);
PAINT GREEN (-8200 4500);
DISPLAY INVISIBLE (-8200 4500);
FORCEPROP 1 LAST COMMENT_BODY TRUE
J 0
(-8400 4525);
DISPLAY 0.872340 (-8400 4525);
PAINT GREEN (-8400 4525);
DISPLAY INVISIBLE (-8400 4525);
FORCEPROP 2 LAST PATH I182
J 0
(-8475 4700);
DISPLAY 0.808511 (-8475 4700);
DISPLAY INVISIBLE (-8475 4700);
FORCEADD OFFPAGE..1
(-8525 4725);
FORCEPROP 2 LAST $XR0 12 
J 0
(-8746 4725);
DISPLAY 0.638298 (-8746 4725);
PAINT MONO (-8746 4725);
FORCEPROP 2 LAST CDS_LIB mstr_standard
J 0
(-8525 4725);
DISPLAY 0.808511 (-8525 4725);
DISPLAY INVISIBLE (-8525 4725);
FORCEPROP 1 LAST OFFPAGE TRUE
J 0
(-8200 4600);
DISPLAY 0.872340 (-8200 4600);
PAINT GREEN (-8200 4600);
DISPLAY INVISIBLE (-8200 4600);
FORCEPROP 1 LAST COMMENT_BODY TRUE
J 0
(-8400 4625);
DISPLAY 0.872340 (-8400 4625);
PAINT GREEN (-8400 4625);
DISPLAY INVISIBLE (-8400 4625);
FORCEPROP 2 LAST PATH I183
J 0
(-8475 4800);
DISPLAY 0.808511 (-8475 4800);
DISPLAY INVISIBLE (-8475 4800);
FORCEADD OFFPAGE..1
(-8525 4775);
FORCEPROP 2 LAST $XR0 12 
J 0
(-8746 4775);
DISPLAY 0.638298 (-8746 4775);
PAINT MONO (-8746 4775);
FORCEPROP 2 LAST CDS_LIB mstr_standard
J 0
(-8525 4775);
DISPLAY 0.723404 (-8525 4775);
PAINT MONO (-8525 4775);
DISPLAY INVISIBLE (-8525 4775);
FORCEPROP 1 LAST OFFPAGE TRUE
J 0
(-8200 4650);
DISPLAY 0.872340 (-8200 4650);
PAINT GREEN (-8200 4650);
DISPLAY INVISIBLE (-8200 4650);
FORCEPROP 1 LAST COMMENT_BODY TRUE
J 0
(-8400 4675);
DISPLAY 0.872340 (-8400 4675);
PAINT GREEN (-8400 4675);
DISPLAY INVISIBLE (-8400 4675);
FORCEPROP 2 LAST PATH I184
J 0
(-8475 4850);
DISPLAY 0.808511 (-8475 4850);
DISPLAY INVISIBLE (-8475 4850);
FORCEADD OFFPAGE..1
(-8525 4925);
FORCEPROP 2 LAST $XR0 12 
J 0
(-8746 4925);
DISPLAY 0.638298 (-8746 4925);
PAINT MONO (-8746 4925);
FORCEPROP 2 LAST CDS_LIB mstr_standard
J 0
(-8525 4925);
DISPLAY 0.723404 (-8525 4925);
PAINT MONO (-8525 4925);
DISPLAY INVISIBLE (-8525 4925);
FORCEPROP 1 LAST OFFPAGE TRUE
J 0
(-8200 4800);
DISPLAY 0.872340 (-8200 4800);
PAINT GREEN (-8200 4800);
DISPLAY INVISIBLE (-8200 4800);
FORCEPROP 1 LAST COMMENT_BODY TRUE
J 0
(-8400 4825);
DISPLAY 0.872340 (-8400 4825);
PAINT GREEN (-8400 4825);
DISPLAY INVISIBLE (-8400 4825);
FORCEPROP 2 LAST PATH I185
J 0
(-8475 5000);
DISPLAY 0.808511 (-8475 5000);
DISPLAY INVISIBLE (-8475 5000);
FORCEADD OFFPAGE..1
(-8525 4875);
FORCEPROP 2 LAST $XR0 12 
J 0
(-8746 4875);
DISPLAY 0.638298 (-8746 4875);
PAINT MONO (-8746 4875);
FORCEPROP 2 LAST CDS_LIB mstr_standard
J 0
(-8525 4875);
DISPLAY 0.808511 (-8525 4875);
DISPLAY INVISIBLE (-8525 4875);
FORCEPROP 1 LAST OFFPAGE TRUE
J 0
(-8200 4750);
DISPLAY 0.872340 (-8200 4750);
PAINT GREEN (-8200 4750);
DISPLAY INVISIBLE (-8200 4750);
FORCEPROP 1 LAST COMMENT_BODY TRUE
J 0
(-8400 4775);
DISPLAY 0.872340 (-8400 4775);
PAINT GREEN (-8400 4775);
DISPLAY INVISIBLE (-8400 4775);
FORCEPROP 2 LAST PATH I186
J 0
(-8475 4950);
DISPLAY 0.808511 (-8475 4950);
DISPLAY INVISIBLE (-8475 4950);
FORCEADD TAP..1
R 2
(-7925 3575);
FORCEPROP 3 LASTPIN (-7875 3575) SIG_NAME M_C_CPU0_SB_CB<1>
J 0
(-7865 3585);
DISPLAY 0.659574 (-7865 3585);
PAINT MONO (-7865 3585);
DISPLAY INVISIBLE (-7865 3585);
FORCEPROP 1 LASTPIN (-7875 3575) BN 1
J 2
(-7863 3583);
DISPLAY 0.489362 (-7863 3583);
PAINT GREEN (-7863 3583);
FORCEPROP 2 LAST CDS_LIB mstr_standard
J 0
(-7925 3575);
DISPLAY 0.723404 (-7925 3575);
PAINT MONO (-7925 3575);
DISPLAY INVISIBLE (-7925 3575);
FORCEPROP 1 LAST BODY_TYPE PLUMBING
J 2
(-7925 3625);
DISPLAY 0.872340 (-7925 3625);
PAINT GREEN (-7925 3625);
DISPLAY INVISIBLE (-7925 3625);
FORCEPROP 1 LAST HDL_TAP TRUE
J 2
(-8250 3450);
DISPLAY 0.872340 (-8250 3450);
DISPLAY INVISIBLE (-8250 3450);
FORCEPROP 1 LAST PATH I187
J 2
(-7923 3575);
DISPLAY 0.872340 (-7923 3575);
PAINT GREEN (-7923 3575);
DISPLAY INVISIBLE (-7923 3575);
FORCEADD TAP..1
R 2
(-7925 3625);
FORCEPROP 3 LASTPIN (-7875 3625) SIG_NAME M_C_CPU0_SB_CB<2>
J 0
(-7865 3635);
DISPLAY 0.659574 (-7865 3635);
PAINT MONO (-7865 3635);
DISPLAY INVISIBLE (-7865 3635);
FORCEPROP 1 LASTPIN (-7875 3625) BN 2
J 2
(-7863 3633);
DISPLAY 0.489362 (-7863 3633);
PAINT GREEN (-7863 3633);
FORCEPROP 2 LAST CDS_LIB mstr_standard
J 0
(-7925 3625);
DISPLAY 0.723404 (-7925 3625);
PAINT MONO (-7925 3625);
DISPLAY INVISIBLE (-7925 3625);
FORCEPROP 1 LAST BODY_TYPE PLUMBING
J 2
(-7925 3675);
DISPLAY 0.872340 (-7925 3675);
PAINT GREEN (-7925 3675);
DISPLAY INVISIBLE (-7925 3675);
FORCEPROP 1 LAST HDL_TAP TRUE
J 2
(-8250 3500);
DISPLAY 0.872340 (-8250 3500);
DISPLAY INVISIBLE (-8250 3500);
FORCEPROP 1 LAST PATH I188
J 2
(-7923 3625);
DISPLAY 0.872340 (-7923 3625);
PAINT GREEN (-7923 3625);
DISPLAY INVISIBLE (-7923 3625);
FORCEADD TAP..1
R 2
(-7925 3525);
FORCEPROP 3 LASTPIN (-7875 3525) SIG_NAME M_C_CPU0_SB_CB<0>
J 0
(-7865 3535);
DISPLAY 0.659574 (-7865 3535);
PAINT MONO (-7865 3535);
DISPLAY INVISIBLE (-7865 3535);
FORCEPROP 1 LASTPIN (-7875 3525) BN 0
J 2
(-7863 3533);
DISPLAY 0.489362 (-7863 3533);
PAINT GREEN (-7863 3533);
FORCEPROP 2 LAST CDS_LIB mstr_standard
J 0
(-7925 3525);
DISPLAY 0.723404 (-7925 3525);
PAINT MONO (-7925 3525);
DISPLAY INVISIBLE (-7925 3525);
FORCEPROP 1 LAST BODY_TYPE PLUMBING
J 2
(-7925 3575);
DISPLAY 0.872340 (-7925 3575);
PAINT GREEN (-7925 3575);
DISPLAY INVISIBLE (-7925 3575);
FORCEPROP 1 LAST HDL_TAP TRUE
J 2
(-8250 3400);
DISPLAY 0.872340 (-8250 3400);
DISPLAY INVISIBLE (-8250 3400);
FORCEPROP 1 LAST PATH I189
J 2
(-7923 3525);
DISPLAY 0.872340 (-7923 3525);
PAINT GREEN (-7923 3525);
DISPLAY INVISIBLE (-7923 3525);
FORCEADD TAP..1
R 2
(-7925 3675);
FORCEPROP 3 LASTPIN (-7875 3675) SIG_NAME M_C_CPU0_SB_CB<3>
J 0
(-7865 3685);
DISPLAY 0.659574 (-7865 3685);
PAINT MONO (-7865 3685);
DISPLAY INVISIBLE (-7865 3685);
FORCEPROP 1 LASTPIN (-7875 3675) BN 3
J 2
(-7863 3683);
DISPLAY 0.489362 (-7863 3683);
PAINT GREEN (-7863 3683);
FORCEPROP 2 LAST CDS_LIB mstr_standard
J 0
(-7925 3675);
DISPLAY 0.723404 (-7925 3675);
PAINT MONO (-7925 3675);
DISPLAY INVISIBLE (-7925 3675);
FORCEPROP 1 LAST BODY_TYPE PLUMBING
J 2
(-7925 3725);
DISPLAY 0.872340 (-7925 3725);
PAINT GREEN (-7925 3725);
DISPLAY INVISIBLE (-7925 3725);
FORCEPROP 1 LAST HDL_TAP TRUE
J 2
(-8250 3550);
DISPLAY 0.872340 (-8250 3550);
DISPLAY INVISIBLE (-8250 3550);
FORCEPROP 1 LAST PATH I190
J 2
(-7923 3675);
DISPLAY 0.872340 (-7923 3675);
PAINT GREEN (-7923 3675);
DISPLAY INVISIBLE (-7923 3675);
FORCEADD TAP..1
R 2
(-7925 3725);
FORCEPROP 3 LASTPIN (-7875 3725) SIG_NAME M_C_CPU0_SB_CB<4>
J 0
(-7865 3735);
DISPLAY 0.659574 (-7865 3735);
PAINT MONO (-7865 3735);
DISPLAY INVISIBLE (-7865 3735);
FORCEPROP 1 LASTPIN (-7875 3725) BN 4
J 2
(-7863 3733);
DISPLAY 0.489362 (-7863 3733);
PAINT GREEN (-7863 3733);
FORCEPROP 2 LAST CDS_LIB mstr_standard
J 0
(-7925 3725);
DISPLAY 0.723404 (-7925 3725);
PAINT MONO (-7925 3725);
DISPLAY INVISIBLE (-7925 3725);
FORCEPROP 1 LAST BODY_TYPE PLUMBING
J 2
(-7925 3775);
DISPLAY 0.872340 (-7925 3775);
PAINT GREEN (-7925 3775);
DISPLAY INVISIBLE (-7925 3775);
FORCEPROP 1 LAST HDL_TAP TRUE
J 2
(-8250 3600);
DISPLAY 0.872340 (-8250 3600);
DISPLAY INVISIBLE (-8250 3600);
FORCEPROP 1 LAST PATH I191
J 2
(-7923 3725);
DISPLAY 0.872340 (-7923 3725);
PAINT GREEN (-7923 3725);
DISPLAY INVISIBLE (-7923 3725);
FORCEADD TAP..1
R 2
(-7925 3775);
FORCEPROP 3 LASTPIN (-7875 3775) SIG_NAME M_C_CPU0_SB_CB<5>
J 0
(-7865 3785);
DISPLAY 0.659574 (-7865 3785);
PAINT MONO (-7865 3785);
DISPLAY INVISIBLE (-7865 3785);
FORCEPROP 1 LASTPIN (-7875 3775) BN 5
J 2
(-7863 3783);
DISPLAY 0.489362 (-7863 3783);
PAINT GREEN (-7863 3783);
FORCEPROP 2 LAST CDS_LIB mstr_standard
J 0
(-7925 3775);
DISPLAY 0.723404 (-7925 3775);
PAINT MONO (-7925 3775);
DISPLAY INVISIBLE (-7925 3775);
FORCEPROP 1 LAST BODY_TYPE PLUMBING
J 2
(-7925 3825);
DISPLAY 0.872340 (-7925 3825);
PAINT GREEN (-7925 3825);
DISPLAY INVISIBLE (-7925 3825);
FORCEPROP 1 LAST HDL_TAP TRUE
J 2
(-8250 3650);
DISPLAY 0.872340 (-8250 3650);
DISPLAY INVISIBLE (-8250 3650);
FORCEPROP 1 LAST PATH I192
J 2
(-7923 3775);
DISPLAY 0.872340 (-7923 3775);
PAINT GREEN (-7923 3775);
DISPLAY INVISIBLE (-7923 3775);
FORCEADD TAP..1
R 2
(-7925 3875);
FORCEPROP 3 LASTPIN (-7875 3875) SIG_NAME M_C_CPU0_SB_CB<7>
J 0
(-7865 3885);
DISPLAY 0.659574 (-7865 3885);
PAINT MONO (-7865 3885);
DISPLAY INVISIBLE (-7865 3885);
FORCEPROP 1 LASTPIN (-7875 3875) BN 7
J 2
(-7863 3883);
DISPLAY 0.489362 (-7863 3883);
PAINT GREEN (-7863 3883);
FORCEPROP 2 LAST CDS_LIB mstr_standard
J 0
(-7925 3875);
DISPLAY 0.723404 (-7925 3875);
PAINT MONO (-7925 3875);
DISPLAY INVISIBLE (-7925 3875);
FORCEPROP 1 LAST BODY_TYPE PLUMBING
J 2
(-7925 3925);
DISPLAY 0.872340 (-7925 3925);
PAINT GREEN (-7925 3925);
DISPLAY INVISIBLE (-7925 3925);
FORCEPROP 1 LAST HDL_TAP TRUE
J 2
(-8250 3750);
DISPLAY 0.872340 (-8250 3750);
DISPLAY INVISIBLE (-8250 3750);
FORCEPROP 1 LAST PATH I193
J 2
(-7923 3875);
DISPLAY 0.872340 (-7923 3875);
PAINT GREEN (-7923 3875);
DISPLAY INVISIBLE (-7923 3875);
FORCEADD TAP..1
R 2
(-7925 3825);
FORCEPROP 3 LASTPIN (-7875 3825) SIG_NAME M_C_CPU0_SB_CB<6>
J 0
(-7865 3835);
DISPLAY 0.659574 (-7865 3835);
PAINT MONO (-7865 3835);
DISPLAY INVISIBLE (-7865 3835);
FORCEPROP 1 LASTPIN (-7875 3825) BN 6
J 2
(-7863 3833);
DISPLAY 0.489362 (-7863 3833);
PAINT GREEN (-7863 3833);
FORCEPROP 2 LAST CDS_LIB mstr_standard
J 0
(-7925 3825);
DISPLAY 0.723404 (-7925 3825);
PAINT MONO (-7925 3825);
DISPLAY INVISIBLE (-7925 3825);
FORCEPROP 1 LAST BODY_TYPE PLUMBING
J 2
(-7925 3875);
DISPLAY 0.872340 (-7925 3875);
PAINT GREEN (-7925 3875);
DISPLAY INVISIBLE (-7925 3875);
FORCEPROP 1 LAST HDL_TAP TRUE
J 2
(-8250 3700);
DISPLAY 0.872340 (-8250 3700);
DISPLAY INVISIBLE (-8250 3700);
FORCEPROP 1 LAST PATH I194
J 2
(-7923 3825);
DISPLAY 0.872340 (-7923 3825);
PAINT GREEN (-7923 3825);
DISPLAY INVISIBLE (-7923 3825);
FORCEADD TAP..1
R 2
(-7925 4075);
FORCEPROP 3 LASTPIN (-7875 4075) SIG_NAME M_C_CPU0_SA_CB<2>
J 0
(-7865 4085);
DISPLAY 0.659574 (-7865 4085);
PAINT MONO (-7865 4085);
DISPLAY INVISIBLE (-7865 4085);
FORCEPROP 1 LASTPIN (-7875 4075) BN 2
J 2
(-7863 4083);
DISPLAY 0.489362 (-7863 4083);
PAINT GREEN (-7863 4083);
FORCEPROP 2 LAST CDS_LIB mstr_standard
J 0
(-7925 4075);
DISPLAY 0.723404 (-7925 4075);
PAINT MONO (-7925 4075);
DISPLAY INVISIBLE (-7925 4075);
FORCEPROP 1 LAST BODY_TYPE PLUMBING
J 2
(-7925 4125);
DISPLAY 0.872340 (-7925 4125);
PAINT GREEN (-7925 4125);
DISPLAY INVISIBLE (-7925 4125);
FORCEPROP 1 LAST HDL_TAP TRUE
J 2
(-8250 3950);
DISPLAY 0.872340 (-8250 3950);
DISPLAY INVISIBLE (-8250 3950);
FORCEPROP 1 LAST PATH I195
J 2
(-7923 4075);
DISPLAY 0.872340 (-7923 4075);
PAINT GREEN (-7923 4075);
DISPLAY INVISIBLE (-7923 4075);
FORCEADD TAP..1
R 2
(-7925 4025);
FORCEPROP 3 LASTPIN (-7875 4025) SIG_NAME M_C_CPU0_SA_CB<1>
J 0
(-7865 4035);
DISPLAY 0.659574 (-7865 4035);
PAINT MONO (-7865 4035);
DISPLAY INVISIBLE (-7865 4035);
FORCEPROP 1 LASTPIN (-7875 4025) BN 1
J 2
(-7863 4033);
DISPLAY 0.489362 (-7863 4033);
PAINT GREEN (-7863 4033);
FORCEPROP 2 LAST CDS_LIB mstr_standard
J 0
(-7925 4025);
DISPLAY 0.723404 (-7925 4025);
PAINT MONO (-7925 4025);
DISPLAY INVISIBLE (-7925 4025);
FORCEPROP 1 LAST BODY_TYPE PLUMBING
J 2
(-7925 4075);
DISPLAY 0.872340 (-7925 4075);
PAINT GREEN (-7925 4075);
DISPLAY INVISIBLE (-7925 4075);
FORCEPROP 1 LAST HDL_TAP TRUE
J 2
(-8250 3900);
DISPLAY 0.872340 (-8250 3900);
DISPLAY INVISIBLE (-8250 3900);
FORCEPROP 1 LAST PATH I196
J 2
(-7923 4025);
DISPLAY 0.872340 (-7923 4025);
PAINT GREEN (-7923 4025);
DISPLAY INVISIBLE (-7923 4025);
FORCEADD TAP..1
R 2
(-7925 3975);
FORCEPROP 3 LASTPIN (-7875 3975) SIG_NAME M_C_CPU0_SA_CB<0>
J 0
(-7865 3985);
DISPLAY 0.659574 (-7865 3985);
PAINT MONO (-7865 3985);
DISPLAY INVISIBLE (-7865 3985);
FORCEPROP 1 LASTPIN (-7875 3975) BN 0
J 2
(-7863 3983);
DISPLAY 0.489362 (-7863 3983);
PAINT GREEN (-7863 3983);
FORCEPROP 2 LAST CDS_LIB mstr_standard
J 0
(-7925 3975);
DISPLAY 0.723404 (-7925 3975);
PAINT MONO (-7925 3975);
DISPLAY INVISIBLE (-7925 3975);
FORCEPROP 1 LAST BODY_TYPE PLUMBING
J 2
(-7925 4025);
DISPLAY 0.872340 (-7925 4025);
PAINT GREEN (-7925 4025);
DISPLAY INVISIBLE (-7925 4025);
FORCEPROP 1 LAST HDL_TAP TRUE
J 2
(-8250 3850);
DISPLAY 0.872340 (-8250 3850);
DISPLAY INVISIBLE (-8250 3850);
FORCEPROP 1 LAST PATH I197
J 2
(-7923 3975);
DISPLAY 0.872340 (-7923 3975);
PAINT GREEN (-7923 3975);
DISPLAY INVISIBLE (-7923 3975);
FORCEADD TAP..1
R 2
(-7925 4125);
FORCEPROP 3 LASTPIN (-7875 4125) SIG_NAME M_C_CPU0_SA_CB<3>
J 0
(-7865 4135);
DISPLAY 0.659574 (-7865 4135);
PAINT MONO (-7865 4135);
DISPLAY INVISIBLE (-7865 4135);
FORCEPROP 1 LASTPIN (-7875 4125) BN 3
J 2
(-7863 4133);
DISPLAY 0.489362 (-7863 4133);
PAINT GREEN (-7863 4133);
FORCEPROP 2 LAST CDS_LIB mstr_standard
J 0
(-7925 4125);
DISPLAY 0.723404 (-7925 4125);
PAINT MONO (-7925 4125);
DISPLAY INVISIBLE (-7925 4125);
FORCEPROP 1 LAST BODY_TYPE PLUMBING
J 2
(-7925 4175);
DISPLAY 0.872340 (-7925 4175);
PAINT GREEN (-7925 4175);
DISPLAY INVISIBLE (-7925 4175);
FORCEPROP 1 LAST HDL_TAP TRUE
J 2
(-8250 4000);
DISPLAY 0.872340 (-8250 4000);
DISPLAY INVISIBLE (-8250 4000);
FORCEPROP 1 LAST PATH I198
J 2
(-7923 4125);
DISPLAY 0.872340 (-7923 4125);
PAINT GREEN (-7923 4125);
DISPLAY INVISIBLE (-7923 4125);
FORCEADD TAP..1
R 2
(-7925 4175);
FORCEPROP 3 LASTPIN (-7875 4175) SIG_NAME M_C_CPU0_SA_CB<4>
J 0
(-7865 4185);
DISPLAY 0.659574 (-7865 4185);
PAINT MONO (-7865 4185);
DISPLAY INVISIBLE (-7865 4185);
FORCEPROP 1 LASTPIN (-7875 4175) BN 4
J 2
(-7863 4183);
DISPLAY 0.489362 (-7863 4183);
PAINT GREEN (-7863 4183);
FORCEPROP 2 LAST CDS_LIB mstr_standard
J 0
(-7925 4175);
DISPLAY 0.723404 (-7925 4175);
PAINT MONO (-7925 4175);
DISPLAY INVISIBLE (-7925 4175);
FORCEPROP 1 LAST BODY_TYPE PLUMBING
J 2
(-7925 4225);
DISPLAY 0.872340 (-7925 4225);
PAINT GREEN (-7925 4225);
DISPLAY INVISIBLE (-7925 4225);
FORCEPROP 1 LAST HDL_TAP TRUE
J 2
(-8250 4050);
DISPLAY 0.872340 (-8250 4050);
DISPLAY INVISIBLE (-8250 4050);
FORCEPROP 1 LAST PATH I199
J 2
(-7923 4175);
DISPLAY 0.872340 (-7923 4175);
PAINT GREEN (-7923 4175);
DISPLAY INVISIBLE (-7923 4175);
FORCEADD TAP..1
R 2
(-7925 4225);
FORCEPROP 3 LASTPIN (-7875 4225) SIG_NAME M_C_CPU0_SA_CB<5>
J 0
(-7865 4235);
DISPLAY 0.659574 (-7865 4235);
PAINT MONO (-7865 4235);
DISPLAY INVISIBLE (-7865 4235);
FORCEPROP 1 LASTPIN (-7875 4225) BN 5
J 2
(-7863 4233);
DISPLAY 0.489362 (-7863 4233);
PAINT GREEN (-7863 4233);
FORCEPROP 2 LAST CDS_LIB mstr_standard
J 0
(-7925 4225);
DISPLAY 0.723404 (-7925 4225);
PAINT MONO (-7925 4225);
DISPLAY INVISIBLE (-7925 4225);
FORCEPROP 1 LAST BODY_TYPE PLUMBING
J 2
(-7925 4275);
DISPLAY 0.872340 (-7925 4275);
PAINT GREEN (-7925 4275);
DISPLAY INVISIBLE (-7925 4275);
FORCEPROP 1 LAST HDL_TAP TRUE
J 2
(-8250 4100);
DISPLAY 0.872340 (-8250 4100);
DISPLAY INVISIBLE (-8250 4100);
FORCEPROP 1 LAST PATH I200
J 2
(-7923 4225);
DISPLAY 0.872340 (-7923 4225);
PAINT GREEN (-7923 4225);
DISPLAY INVISIBLE (-7923 4225);
FORCEADD TAP..1
R 2
(-7925 4275);
FORCEPROP 3 LASTPIN (-7875 4275) SIG_NAME M_C_CPU0_SA_CB<6>
J 0
(-7865 4285);
DISPLAY 0.659574 (-7865 4285);
PAINT MONO (-7865 4285);
DISPLAY INVISIBLE (-7865 4285);
FORCEPROP 1 LASTPIN (-7875 4275) BN 6
J 2
(-7863 4283);
DISPLAY 0.489362 (-7863 4283);
PAINT GREEN (-7863 4283);
FORCEPROP 2 LAST CDS_LIB mstr_standard
J 0
(-7925 4275);
DISPLAY 0.723404 (-7925 4275);
PAINT MONO (-7925 4275);
DISPLAY INVISIBLE (-7925 4275);
FORCEPROP 1 LAST BODY_TYPE PLUMBING
J 2
(-7925 4325);
DISPLAY 0.872340 (-7925 4325);
PAINT GREEN (-7925 4325);
DISPLAY INVISIBLE (-7925 4325);
FORCEPROP 1 LAST HDL_TAP TRUE
J 2
(-8250 4150);
DISPLAY 0.872340 (-8250 4150);
DISPLAY INVISIBLE (-8250 4150);
FORCEPROP 1 LAST PATH I201
J 2
(-7923 4275);
DISPLAY 0.872340 (-7923 4275);
PAINT GREEN (-7923 4275);
DISPLAY INVISIBLE (-7923 4275);
FORCEADD TAP..1
R 2
(-7925 4325);
FORCEPROP 3 LASTPIN (-7875 4325) SIG_NAME M_C_CPU0_SA_CB<7>
J 0
(-7865 4335);
DISPLAY 0.659574 (-7865 4335);
PAINT MONO (-7865 4335);
DISPLAY INVISIBLE (-7865 4335);
FORCEPROP 1 LASTPIN (-7875 4325) BN 7
J 2
(-7863 4333);
DISPLAY 0.489362 (-7863 4333);
PAINT GREEN (-7863 4333);
FORCEPROP 2 LAST CDS_LIB mstr_standard
J 0
(-7925 4325);
DISPLAY 0.723404 (-7925 4325);
PAINT MONO (-7925 4325);
DISPLAY INVISIBLE (-7925 4325);
FORCEPROP 1 LAST BODY_TYPE PLUMBING
J 2
(-7925 4375);
DISPLAY 0.872340 (-7925 4375);
PAINT GREEN (-7925 4375);
DISPLAY INVISIBLE (-7925 4375);
FORCEPROP 1 LAST HDL_TAP TRUE
J 2
(-8250 4200);
DISPLAY 0.872340 (-8250 4200);
DISPLAY INVISIBLE (-8250 4200);
FORCEPROP 1 LAST PATH I202
J 2
(-7923 4325);
DISPLAY 0.872340 (-7923 4325);
PAINT GREEN (-7923 4325);
DISPLAY INVISIBLE (-7923 4325);
FORCEADD TAP..1
R 2
(-7925 5175);
FORCEPROP 3 LASTPIN (-7875 5175) SIG_NAME M_C_CPU0_SB_CA<3>
J 0
(-7865 5185);
DISPLAY 0.659574 (-7865 5185);
PAINT MONO (-7865 5185);
DISPLAY INVISIBLE (-7865 5185);
FORCEPROP 1 LASTPIN (-7875 5175) BN 3
J 2
(-7863 5183);
DISPLAY 0.489362 (-7863 5183);
PAINT GREEN (-7863 5183);
FORCEPROP 2 LAST CDS_LIB mstr_standard
J 0
(-7925 5175);
DISPLAY 0.723404 (-7925 5175);
PAINT MONO (-7925 5175);
DISPLAY INVISIBLE (-7925 5175);
FORCEPROP 1 LAST BODY_TYPE PLUMBING
J 2
(-7925 5225);
DISPLAY 0.872340 (-7925 5225);
PAINT GREEN (-7925 5225);
DISPLAY INVISIBLE (-7925 5225);
FORCEPROP 1 LAST HDL_TAP TRUE
J 2
(-8250 5050);
DISPLAY 0.872340 (-8250 5050);
DISPLAY INVISIBLE (-8250 5050);
FORCEPROP 1 LAST PATH I203
J 2
(-7923 5175);
DISPLAY 0.872340 (-7923 5175);
PAINT GREEN (-7923 5175);
DISPLAY INVISIBLE (-7923 5175);
FORCEADD TAP..1
R 2
(-7925 5075);
FORCEPROP 3 LASTPIN (-7875 5075) SIG_NAME M_C_CPU0_SB_CA<1>
J 0
(-7865 5085);
DISPLAY 0.659574 (-7865 5085);
PAINT MONO (-7865 5085);
DISPLAY INVISIBLE (-7865 5085);
FORCEPROP 1 LASTPIN (-7875 5075) BN 1
J 2
(-7863 5083);
DISPLAY 0.489362 (-7863 5083);
PAINT GREEN (-7863 5083);
FORCEPROP 2 LAST CDS_LIB mstr_standard
J 0
(-7925 5075);
DISPLAY 0.723404 (-7925 5075);
PAINT MONO (-7925 5075);
DISPLAY INVISIBLE (-7925 5075);
FORCEPROP 1 LAST BODY_TYPE PLUMBING
J 2
(-7925 5125);
DISPLAY 0.872340 (-7925 5125);
PAINT GREEN (-7925 5125);
DISPLAY INVISIBLE (-7925 5125);
FORCEPROP 1 LAST HDL_TAP TRUE
J 2
(-8250 4950);
DISPLAY 0.872340 (-8250 4950);
DISPLAY INVISIBLE (-8250 4950);
FORCEPROP 1 LAST PATH I204
J 2
(-7923 5075);
DISPLAY 0.872340 (-7923 5075);
PAINT GREEN (-7923 5075);
DISPLAY INVISIBLE (-7923 5075);
FORCEADD TAP..1
R 2
(-7925 5025);
FORCEPROP 3 LASTPIN (-7875 5025) SIG_NAME M_C_CPU0_SB_CA<0>
J 0
(-7865 5035);
DISPLAY 0.659574 (-7865 5035);
PAINT MONO (-7865 5035);
DISPLAY INVISIBLE (-7865 5035);
FORCEPROP 1 LASTPIN (-7875 5025) BN 0
J 2
(-7863 5033);
DISPLAY 0.489362 (-7863 5033);
PAINT GREEN (-7863 5033);
FORCEPROP 2 LAST CDS_LIB mstr_standard
J 0
(-7925 5025);
DISPLAY 0.723404 (-7925 5025);
PAINT MONO (-7925 5025);
DISPLAY INVISIBLE (-7925 5025);
FORCEPROP 1 LAST BODY_TYPE PLUMBING
J 2
(-7925 5075);
DISPLAY 0.872340 (-7925 5075);
PAINT GREEN (-7925 5075);
DISPLAY INVISIBLE (-7925 5075);
FORCEPROP 1 LAST HDL_TAP TRUE
J 2
(-8250 4900);
DISPLAY 0.872340 (-8250 4900);
DISPLAY INVISIBLE (-8250 4900);
FORCEPROP 1 LAST PATH I205
J 2
(-7923 5025);
DISPLAY 0.872340 (-7923 5025);
PAINT GREEN (-7923 5025);
DISPLAY INVISIBLE (-7923 5025);
FORCEADD TAP..1
R 2
(-7925 5125);
FORCEPROP 3 LASTPIN (-7875 5125) SIG_NAME M_C_CPU0_SB_CA<2>
J 0
(-7865 5135);
DISPLAY 0.659574 (-7865 5135);
PAINT MONO (-7865 5135);
DISPLAY INVISIBLE (-7865 5135);
FORCEPROP 1 LASTPIN (-7875 5125) BN 2
J 2
(-7863 5133);
DISPLAY 0.489362 (-7863 5133);
PAINT GREEN (-7863 5133);
FORCEPROP 2 LAST CDS_LIB mstr_standard
J 0
(-7925 5125);
DISPLAY 0.723404 (-7925 5125);
PAINT MONO (-7925 5125);
DISPLAY INVISIBLE (-7925 5125);
FORCEPROP 1 LAST BODY_TYPE PLUMBING
J 2
(-7925 5175);
DISPLAY 0.872340 (-7925 5175);
PAINT GREEN (-7925 5175);
DISPLAY INVISIBLE (-7925 5175);
FORCEPROP 1 LAST HDL_TAP TRUE
J 2
(-8250 5000);
DISPLAY 0.872340 (-8250 5000);
DISPLAY INVISIBLE (-8250 5000);
FORCEPROP 1 LAST PATH I206
J 2
(-7923 5125);
DISPLAY 0.872340 (-7923 5125);
PAINT GREEN (-7923 5125);
DISPLAY INVISIBLE (-7923 5125);
FORCEADD TAP..1
(-6225 2575);
FORCEPROP 3 LASTPIN (-6275 2575) SIG_NAME M_C_CPU0_SB_DQ<1>
J 0
(-6265 2585);
DISPLAY 0.659574 (-6265 2585);
PAINT MONO (-6265 2585);
DISPLAY INVISIBLE (-6265 2585);
FORCEPROP 1 LASTPIN (-6275 2575) BN 1
J 0
(-6287 2583);
DISPLAY 0.489362 (-6287 2583);
PAINT GREEN (-6287 2583);
FORCEPROP 2 LAST CDS_LIB mstr_standard
J 0
(-6225 2575);
DISPLAY 0.723404 (-6225 2575);
PAINT MONO (-6225 2575);
DISPLAY INVISIBLE (-6225 2575);
FORCEPROP 1 LAST BODY_TYPE PLUMBING
J 0
(-6225 2625);
DISPLAY 0.872340 (-6225 2625);
PAINT GREEN (-6225 2625);
DISPLAY INVISIBLE (-6225 2625);
FORCEPROP 1 LAST HDL_TAP TRUE
J 0
(-5900 2450);
DISPLAY 0.872340 (-5900 2450);
DISPLAY INVISIBLE (-5900 2450);
FORCEPROP 1 LAST PATH I207
J 0
(-6227 2575);
DISPLAY 0.872340 (-6227 2575);
PAINT GREEN (-6227 2575);
DISPLAY INVISIBLE (-6227 2575);
FORCEADD TAP..1
(-6225 2525);
FORCEPROP 3 LASTPIN (-6275 2525) SIG_NAME M_C_CPU0_SB_DQ<0>
J 0
(-6265 2535);
DISPLAY 0.659574 (-6265 2535);
PAINT MONO (-6265 2535);
DISPLAY INVISIBLE (-6265 2535);
FORCEPROP 1 LASTPIN (-6275 2525) BN 0
J 0
(-6287 2533);
DISPLAY 0.489362 (-6287 2533);
PAINT GREEN (-6287 2533);
FORCEPROP 2 LAST CDS_LIB mstr_standard
J 0
(-6225 2525);
DISPLAY 0.723404 (-6225 2525);
PAINT MONO (-6225 2525);
DISPLAY INVISIBLE (-6225 2525);
FORCEPROP 1 LAST BODY_TYPE PLUMBING
J 0
(-6225 2575);
DISPLAY 0.872340 (-6225 2575);
PAINT GREEN (-6225 2575);
DISPLAY INVISIBLE (-6225 2575);
FORCEPROP 1 LAST HDL_TAP TRUE
J 0
(-5900 2400);
DISPLAY 0.872340 (-5900 2400);
DISPLAY INVISIBLE (-5900 2400);
FORCEPROP 1 LAST PATH I208
J 0
(-6227 2525);
DISPLAY 0.872340 (-6227 2525);
PAINT GREEN (-6227 2525);
DISPLAY INVISIBLE (-6227 2525);
FORCEADD TAP..1
(-6225 2625);
FORCEPROP 3 LASTPIN (-6275 2625) SIG_NAME M_C_CPU0_SB_DQ<2>
J 0
(-6265 2635);
DISPLAY 0.659574 (-6265 2635);
PAINT MONO (-6265 2635);
DISPLAY INVISIBLE (-6265 2635);
FORCEPROP 1 LASTPIN (-6275 2625) BN 2
J 0
(-6287 2633);
DISPLAY 0.489362 (-6287 2633);
PAINT GREEN (-6287 2633);
FORCEPROP 2 LAST CDS_LIB mstr_standard
J 0
(-6225 2625);
DISPLAY 0.723404 (-6225 2625);
PAINT MONO (-6225 2625);
DISPLAY INVISIBLE (-6225 2625);
FORCEPROP 1 LAST BODY_TYPE PLUMBING
J 0
(-6225 2675);
DISPLAY 0.872340 (-6225 2675);
PAINT GREEN (-6225 2675);
DISPLAY INVISIBLE (-6225 2675);
FORCEPROP 1 LAST HDL_TAP TRUE
J 0
(-5900 2500);
DISPLAY 0.872340 (-5900 2500);
DISPLAY INVISIBLE (-5900 2500);
FORCEPROP 1 LAST PATH I209
J 0
(-6227 2625);
DISPLAY 0.872340 (-6227 2625);
PAINT GREEN (-6227 2625);
DISPLAY INVISIBLE (-6227 2625);
FORCEADD TAP..1
(-6225 2675);
FORCEPROP 3 LASTPIN (-6275 2675) SIG_NAME M_C_CPU0_SB_DQ<3>
J 0
(-6265 2685);
DISPLAY 0.659574 (-6265 2685);
PAINT MONO (-6265 2685);
DISPLAY INVISIBLE (-6265 2685);
FORCEPROP 1 LASTPIN (-6275 2675) BN 3
J 0
(-6287 2683);
DISPLAY 0.489362 (-6287 2683);
PAINT GREEN (-6287 2683);
FORCEPROP 2 LAST CDS_LIB mstr_standard
J 0
(-6225 2675);
DISPLAY 0.723404 (-6225 2675);
PAINT MONO (-6225 2675);
DISPLAY INVISIBLE (-6225 2675);
FORCEPROP 1 LAST BODY_TYPE PLUMBING
J 0
(-6225 2725);
DISPLAY 0.872340 (-6225 2725);
PAINT GREEN (-6225 2725);
DISPLAY INVISIBLE (-6225 2725);
FORCEPROP 1 LAST HDL_TAP TRUE
J 0
(-5900 2550);
DISPLAY 0.872340 (-5900 2550);
DISPLAY INVISIBLE (-5900 2550);
FORCEPROP 1 LAST PATH I210
J 0
(-6227 2675);
DISPLAY 0.872340 (-6227 2675);
PAINT GREEN (-6227 2675);
DISPLAY INVISIBLE (-6227 2675);
FORCEADD TAP..1
(-6225 2725);
FORCEPROP 3 LASTPIN (-6275 2725) SIG_NAME M_C_CPU0_SB_DQ<4>
J 0
(-6265 2735);
DISPLAY 0.659574 (-6265 2735);
PAINT MONO (-6265 2735);
DISPLAY INVISIBLE (-6265 2735);
FORCEPROP 1 LASTPIN (-6275 2725) BN 4
J 0
(-6287 2733);
DISPLAY 0.489362 (-6287 2733);
PAINT GREEN (-6287 2733);
FORCEPROP 2 LAST CDS_LIB mstr_standard
J 0
(-6225 2725);
DISPLAY 0.723404 (-6225 2725);
PAINT MONO (-6225 2725);
DISPLAY INVISIBLE (-6225 2725);
FORCEPROP 1 LAST BODY_TYPE PLUMBING
J 0
(-6225 2775);
DISPLAY 0.872340 (-6225 2775);
PAINT GREEN (-6225 2775);
DISPLAY INVISIBLE (-6225 2775);
FORCEPROP 1 LAST HDL_TAP TRUE
J 0
(-5900 2600);
DISPLAY 0.872340 (-5900 2600);
DISPLAY INVISIBLE (-5900 2600);
FORCEPROP 1 LAST PATH I211
J 0
(-6227 2725);
DISPLAY 0.872340 (-6227 2725);
PAINT GREEN (-6227 2725);
DISPLAY INVISIBLE (-6227 2725);
FORCEADD TAP..1
(-6225 2775);
FORCEPROP 3 LASTPIN (-6275 2775) SIG_NAME M_C_CPU0_SB_DQ<5>
J 0
(-6265 2785);
DISPLAY 0.659574 (-6265 2785);
PAINT MONO (-6265 2785);
DISPLAY INVISIBLE (-6265 2785);
FORCEPROP 1 LASTPIN (-6275 2775) BN 5
J 0
(-6287 2783);
DISPLAY 0.489362 (-6287 2783);
PAINT GREEN (-6287 2783);
FORCEPROP 2 LAST CDS_LIB mstr_standard
J 0
(-6225 2775);
DISPLAY 0.723404 (-6225 2775);
PAINT MONO (-6225 2775);
DISPLAY INVISIBLE (-6225 2775);
FORCEPROP 1 LAST BODY_TYPE PLUMBING
J 0
(-6225 2825);
DISPLAY 0.872340 (-6225 2825);
PAINT GREEN (-6225 2825);
DISPLAY INVISIBLE (-6225 2825);
FORCEPROP 1 LAST HDL_TAP TRUE
J 0
(-5900 2650);
DISPLAY 0.872340 (-5900 2650);
DISPLAY INVISIBLE (-5900 2650);
FORCEPROP 1 LAST PATH I212
J 0
(-6227 2775);
DISPLAY 0.872340 (-6227 2775);
PAINT GREEN (-6227 2775);
DISPLAY INVISIBLE (-6227 2775);
FORCEADD TAP..1
(-6225 2875);
FORCEPROP 3 LASTPIN (-6275 2875) SIG_NAME M_C_CPU0_SB_DQ<7>
J 0
(-6265 2885);
DISPLAY 0.659574 (-6265 2885);
PAINT MONO (-6265 2885);
DISPLAY INVISIBLE (-6265 2885);
FORCEPROP 1 LASTPIN (-6275 2875) BN 7
J 0
(-6287 2883);
DISPLAY 0.489362 (-6287 2883);
PAINT GREEN (-6287 2883);
FORCEPROP 2 LAST CDS_LIB mstr_standard
J 0
(-6225 2875);
DISPLAY 0.723404 (-6225 2875);
PAINT MONO (-6225 2875);
DISPLAY INVISIBLE (-6225 2875);
FORCEPROP 1 LAST BODY_TYPE PLUMBING
J 0
(-6225 2925);
DISPLAY 0.872340 (-6225 2925);
PAINT GREEN (-6225 2925);
DISPLAY INVISIBLE (-6225 2925);
FORCEPROP 1 LAST HDL_TAP TRUE
J 0
(-5900 2750);
DISPLAY 0.872340 (-5900 2750);
DISPLAY INVISIBLE (-5900 2750);
FORCEPROP 1 LAST PATH I213
J 0
(-6227 2875);
DISPLAY 0.872340 (-6227 2875);
PAINT GREEN (-6227 2875);
DISPLAY INVISIBLE (-6227 2875);
FORCEADD TAP..1
(-6225 2825);
FORCEPROP 3 LASTPIN (-6275 2825) SIG_NAME M_C_CPU0_SB_DQ<6>
J 0
(-6265 2835);
DISPLAY 0.659574 (-6265 2835);
PAINT MONO (-6265 2835);
DISPLAY INVISIBLE (-6265 2835);
FORCEPROP 1 LASTPIN (-6275 2825) BN 6
J 0
(-6287 2833);
DISPLAY 0.489362 (-6287 2833);
PAINT GREEN (-6287 2833);
FORCEPROP 2 LAST CDS_LIB mstr_standard
J 0
(-6225 2825);
DISPLAY 0.723404 (-6225 2825);
PAINT MONO (-6225 2825);
DISPLAY INVISIBLE (-6225 2825);
FORCEPROP 1 LAST BODY_TYPE PLUMBING
J 0
(-6225 2875);
DISPLAY 0.872340 (-6225 2875);
PAINT GREEN (-6225 2875);
DISPLAY INVISIBLE (-6225 2875);
FORCEPROP 1 LAST HDL_TAP TRUE
J 0
(-5900 2700);
DISPLAY 0.872340 (-5900 2700);
DISPLAY INVISIBLE (-5900 2700);
FORCEPROP 1 LAST PATH I214
J 0
(-6227 2825);
DISPLAY 0.872340 (-6227 2825);
PAINT GREEN (-6227 2825);
DISPLAY INVISIBLE (-6227 2825);
FORCEADD TAP..1
(-6225 2925);
FORCEPROP 3 LASTPIN (-6275 2925) SIG_NAME M_C_CPU0_SB_DQ<8>
J 0
(-6265 2935);
DISPLAY 0.659574 (-6265 2935);
PAINT MONO (-6265 2935);
DISPLAY INVISIBLE (-6265 2935);
FORCEPROP 1 LASTPIN (-6275 2925) BN 8
J 0
(-6287 2933);
DISPLAY 0.489362 (-6287 2933);
PAINT GREEN (-6287 2933);
FORCEPROP 2 LAST CDS_LIB mstr_standard
J 0
(-6225 2925);
DISPLAY 0.723404 (-6225 2925);
PAINT MONO (-6225 2925);
DISPLAY INVISIBLE (-6225 2925);
FORCEPROP 1 LAST BODY_TYPE PLUMBING
J 0
(-6225 2975);
DISPLAY 0.872340 (-6225 2975);
PAINT GREEN (-6225 2975);
DISPLAY INVISIBLE (-6225 2975);
FORCEPROP 1 LAST HDL_TAP TRUE
J 0
(-5900 2800);
DISPLAY 0.872340 (-5900 2800);
DISPLAY INVISIBLE (-5900 2800);
FORCEPROP 1 LAST PATH I215
J 0
(-6227 2925);
DISPLAY 0.872340 (-6227 2925);
PAINT GREEN (-6227 2925);
DISPLAY INVISIBLE (-6227 2925);
FORCEADD TAP..1
(-6225 2975);
FORCEPROP 3 LASTPIN (-6275 2975) SIG_NAME M_C_CPU0_SB_DQ<9>
J 0
(-6265 2985);
DISPLAY 0.659574 (-6265 2985);
PAINT MONO (-6265 2985);
DISPLAY INVISIBLE (-6265 2985);
FORCEPROP 1 LASTPIN (-6275 2975) BN 9
J 0
(-6287 2983);
DISPLAY 0.489362 (-6287 2983);
PAINT GREEN (-6287 2983);
FORCEPROP 2 LAST CDS_LIB mstr_standard
J 0
(-6225 2975);
DISPLAY 0.723404 (-6225 2975);
PAINT MONO (-6225 2975);
DISPLAY INVISIBLE (-6225 2975);
FORCEPROP 1 LAST BODY_TYPE PLUMBING
J 0
(-6225 3025);
DISPLAY 0.872340 (-6225 3025);
PAINT GREEN (-6225 3025);
DISPLAY INVISIBLE (-6225 3025);
FORCEPROP 1 LAST HDL_TAP TRUE
J 0
(-5900 2850);
DISPLAY 0.872340 (-5900 2850);
DISPLAY INVISIBLE (-5900 2850);
FORCEPROP 1 LAST PATH I216
J 0
(-6227 2975);
DISPLAY 0.872340 (-6227 2975);
PAINT GREEN (-6227 2975);
DISPLAY INVISIBLE (-6227 2975);
FORCEADD TAP..1
(-6225 3025);
FORCEPROP 3 LASTPIN (-6275 3025) SIG_NAME M_C_CPU0_SB_DQ<10>
J 0
(-6265 3035);
DISPLAY 0.659574 (-6265 3035);
PAINT MONO (-6265 3035);
DISPLAY INVISIBLE (-6265 3035);
FORCEPROP 1 LASTPIN (-6275 3025) BN 10
J 0
(-6287 3033);
DISPLAY 0.489362 (-6287 3033);
PAINT GREEN (-6287 3033);
FORCEPROP 2 LAST CDS_LIB mstr_standard
J 0
(-6225 3025);
DISPLAY 0.723404 (-6225 3025);
PAINT MONO (-6225 3025);
DISPLAY INVISIBLE (-6225 3025);
FORCEPROP 1 LAST BODY_TYPE PLUMBING
J 0
(-6225 3075);
DISPLAY 0.872340 (-6225 3075);
PAINT GREEN (-6225 3075);
DISPLAY INVISIBLE (-6225 3075);
FORCEPROP 1 LAST HDL_TAP TRUE
J 0
(-5900 2900);
DISPLAY 0.872340 (-5900 2900);
DISPLAY INVISIBLE (-5900 2900);
FORCEPROP 1 LAST PATH I217
J 0
(-6227 3025);
DISPLAY 0.872340 (-6227 3025);
PAINT GREEN (-6227 3025);
DISPLAY INVISIBLE (-6227 3025);
FORCEADD TAP..1
(-6225 3075);
FORCEPROP 3 LASTPIN (-6275 3075) SIG_NAME M_C_CPU0_SB_DQ<11>
J 0
(-6265 3085);
DISPLAY 0.659574 (-6265 3085);
PAINT MONO (-6265 3085);
DISPLAY INVISIBLE (-6265 3085);
FORCEPROP 1 LASTPIN (-6275 3075) BN 11
J 0
(-6287 3083);
DISPLAY 0.489362 (-6287 3083);
PAINT GREEN (-6287 3083);
FORCEPROP 2 LAST CDS_LIB mstr_standard
J 0
(-6225 3075);
DISPLAY 0.723404 (-6225 3075);
PAINT MONO (-6225 3075);
DISPLAY INVISIBLE (-6225 3075);
FORCEPROP 1 LAST BODY_TYPE PLUMBING
J 0
(-6225 3125);
DISPLAY 0.872340 (-6225 3125);
PAINT GREEN (-6225 3125);
DISPLAY INVISIBLE (-6225 3125);
FORCEPROP 1 LAST HDL_TAP TRUE
J 0
(-5900 2950);
DISPLAY 0.872340 (-5900 2950);
DISPLAY INVISIBLE (-5900 2950);
FORCEPROP 1 LAST PATH I218
J 0
(-6227 3075);
DISPLAY 0.872340 (-6227 3075);
PAINT GREEN (-6227 3075);
DISPLAY INVISIBLE (-6227 3075);
FORCEADD TAP..1
(-6225 3125);
FORCEPROP 3 LASTPIN (-6275 3125) SIG_NAME M_C_CPU0_SB_DQ<12>
J 0
(-6265 3135);
DISPLAY 0.659574 (-6265 3135);
PAINT MONO (-6265 3135);
DISPLAY INVISIBLE (-6265 3135);
FORCEPROP 1 LASTPIN (-6275 3125) BN 12
J 0
(-6287 3133);
DISPLAY 0.489362 (-6287 3133);
PAINT GREEN (-6287 3133);
FORCEPROP 2 LAST CDS_LIB mstr_standard
J 0
(-6225 3125);
DISPLAY 0.723404 (-6225 3125);
PAINT MONO (-6225 3125);
DISPLAY INVISIBLE (-6225 3125);
FORCEPROP 1 LAST BODY_TYPE PLUMBING
J 0
(-6225 3175);
DISPLAY 0.872340 (-6225 3175);
PAINT GREEN (-6225 3175);
DISPLAY INVISIBLE (-6225 3175);
FORCEPROP 1 LAST HDL_TAP TRUE
J 0
(-5900 3000);
DISPLAY 0.872340 (-5900 3000);
DISPLAY INVISIBLE (-5900 3000);
FORCEPROP 1 LAST PATH I219
J 0
(-6227 3125);
DISPLAY 0.872340 (-6227 3125);
PAINT GREEN (-6227 3125);
DISPLAY INVISIBLE (-6227 3125);
FORCEADD TAP..1
(-6225 3175);
FORCEPROP 3 LASTPIN (-6275 3175) SIG_NAME M_C_CPU0_SB_DQ<13>
J 0
(-6265 3185);
DISPLAY 0.659574 (-6265 3185);
PAINT MONO (-6265 3185);
DISPLAY INVISIBLE (-6265 3185);
FORCEPROP 1 LASTPIN (-6275 3175) BN 13
J 0
(-6287 3183);
DISPLAY 0.489362 (-6287 3183);
PAINT GREEN (-6287 3183);
FORCEPROP 2 LAST CDS_LIB mstr_standard
J 0
(-6225 3175);
DISPLAY 0.723404 (-6225 3175);
PAINT MONO (-6225 3175);
DISPLAY INVISIBLE (-6225 3175);
FORCEPROP 1 LAST BODY_TYPE PLUMBING
J 0
(-6225 3225);
DISPLAY 0.872340 (-6225 3225);
PAINT GREEN (-6225 3225);
DISPLAY INVISIBLE (-6225 3225);
FORCEPROP 1 LAST HDL_TAP TRUE
J 0
(-5900 3050);
DISPLAY 0.872340 (-5900 3050);
DISPLAY INVISIBLE (-5900 3050);
FORCEPROP 1 LAST PATH I220
J 0
(-6227 3175);
DISPLAY 0.872340 (-6227 3175);
PAINT GREEN (-6227 3175);
DISPLAY INVISIBLE (-6227 3175);
FORCEADD TAP..1
(-6225 3275);
FORCEPROP 3 LASTPIN (-6275 3275) SIG_NAME M_C_CPU0_SB_DQ<15>
J 0
(-6265 3285);
DISPLAY 0.659574 (-6265 3285);
PAINT MONO (-6265 3285);
DISPLAY INVISIBLE (-6265 3285);
FORCEPROP 1 LASTPIN (-6275 3275) BN 15
J 0
(-6287 3283);
DISPLAY 0.489362 (-6287 3283);
PAINT GREEN (-6287 3283);
FORCEPROP 2 LAST CDS_LIB mstr_standard
J 0
(-6225 3275);
DISPLAY 0.723404 (-6225 3275);
PAINT MONO (-6225 3275);
DISPLAY INVISIBLE (-6225 3275);
FORCEPROP 1 LAST BODY_TYPE PLUMBING
J 0
(-6225 3325);
DISPLAY 0.872340 (-6225 3325);
PAINT GREEN (-6225 3325);
DISPLAY INVISIBLE (-6225 3325);
FORCEPROP 1 LAST HDL_TAP TRUE
J 0
(-5900 3150);
DISPLAY 0.872340 (-5900 3150);
DISPLAY INVISIBLE (-5900 3150);
FORCEPROP 1 LAST PATH I221
J 0
(-6227 3275);
DISPLAY 0.872340 (-6227 3275);
PAINT GREEN (-6227 3275);
DISPLAY INVISIBLE (-6227 3275);
FORCEADD TAP..1
(-6225 3225);
FORCEPROP 3 LASTPIN (-6275 3225) SIG_NAME M_C_CPU0_SB_DQ<14>
J 0
(-6265 3235);
DISPLAY 0.659574 (-6265 3235);
PAINT MONO (-6265 3235);
DISPLAY INVISIBLE (-6265 3235);
FORCEPROP 1 LASTPIN (-6275 3225) BN 14
J 0
(-6287 3233);
DISPLAY 0.489362 (-6287 3233);
PAINT GREEN (-6287 3233);
FORCEPROP 2 LAST CDS_LIB mstr_standard
J 0
(-6225 3225);
DISPLAY 0.723404 (-6225 3225);
PAINT MONO (-6225 3225);
DISPLAY INVISIBLE (-6225 3225);
FORCEPROP 1 LAST BODY_TYPE PLUMBING
J 0
(-6225 3275);
DISPLAY 0.872340 (-6225 3275);
PAINT GREEN (-6225 3275);
DISPLAY INVISIBLE (-6225 3275);
FORCEPROP 1 LAST HDL_TAP TRUE
J 0
(-5900 3100);
DISPLAY 0.872340 (-5900 3100);
DISPLAY INVISIBLE (-5900 3100);
FORCEPROP 1 LAST PATH I222
J 0
(-6227 3225);
DISPLAY 0.872340 (-6227 3225);
PAINT GREEN (-6227 3225);
DISPLAY INVISIBLE (-6227 3225);
FORCEADD TAP..1
(-6225 3425);
FORCEPROP 3 LASTPIN (-6275 3425) SIG_NAME M_C_CPU0_SB_DQ<18>
J 0
(-6265 3435);
DISPLAY 0.659574 (-6265 3435);
PAINT MONO (-6265 3435);
DISPLAY INVISIBLE (-6265 3435);
FORCEPROP 1 LASTPIN (-6275 3425) BN 18
J 0
(-6287 3433);
DISPLAY 0.489362 (-6287 3433);
PAINT GREEN (-6287 3433);
FORCEPROP 2 LAST CDS_LIB mstr_standard
J 0
(-6225 3425);
DISPLAY 0.723404 (-6225 3425);
PAINT MONO (-6225 3425);
DISPLAY INVISIBLE (-6225 3425);
FORCEPROP 1 LAST BODY_TYPE PLUMBING
J 0
(-6225 3475);
DISPLAY 0.872340 (-6225 3475);
PAINT GREEN (-6225 3475);
DISPLAY INVISIBLE (-6225 3475);
FORCEPROP 1 LAST HDL_TAP TRUE
J 0
(-5900 3300);
DISPLAY 0.872340 (-5900 3300);
DISPLAY INVISIBLE (-5900 3300);
FORCEPROP 1 LAST PATH I223
J 0
(-6227 3425);
DISPLAY 0.872340 (-6227 3425);
PAINT GREEN (-6227 3425);
DISPLAY INVISIBLE (-6227 3425);
FORCEADD TAP..1
(-6225 3375);
FORCEPROP 3 LASTPIN (-6275 3375) SIG_NAME M_C_CPU0_SB_DQ<17>
J 0
(-6265 3385);
DISPLAY 0.659574 (-6265 3385);
PAINT MONO (-6265 3385);
DISPLAY INVISIBLE (-6265 3385);
FORCEPROP 1 LASTPIN (-6275 3375) BN 17
J 0
(-6287 3383);
DISPLAY 0.489362 (-6287 3383);
PAINT GREEN (-6287 3383);
FORCEPROP 2 LAST CDS_LIB mstr_standard
J 0
(-6225 3375);
DISPLAY 0.723404 (-6225 3375);
PAINT MONO (-6225 3375);
DISPLAY INVISIBLE (-6225 3375);
FORCEPROP 1 LAST BODY_TYPE PLUMBING
J 0
(-6225 3425);
DISPLAY 0.872340 (-6225 3425);
PAINT GREEN (-6225 3425);
DISPLAY INVISIBLE (-6225 3425);
FORCEPROP 1 LAST HDL_TAP TRUE
J 0
(-5900 3250);
DISPLAY 0.872340 (-5900 3250);
DISPLAY INVISIBLE (-5900 3250);
FORCEPROP 1 LAST PATH I224
J 0
(-6227 3375);
DISPLAY 0.872340 (-6227 3375);
PAINT GREEN (-6227 3375);
DISPLAY INVISIBLE (-6227 3375);
FORCEADD TAP..1
(-6225 3325);
FORCEPROP 3 LASTPIN (-6275 3325) SIG_NAME M_C_CPU0_SB_DQ<16>
J 0
(-6265 3335);
DISPLAY 0.659574 (-6265 3335);
PAINT MONO (-6265 3335);
DISPLAY INVISIBLE (-6265 3335);
FORCEPROP 1 LASTPIN (-6275 3325) BN 16
J 0
(-6287 3333);
DISPLAY 0.489362 (-6287 3333);
PAINT GREEN (-6287 3333);
FORCEPROP 2 LAST CDS_LIB mstr_standard
J 0
(-6225 3325);
DISPLAY 0.723404 (-6225 3325);
PAINT MONO (-6225 3325);
DISPLAY INVISIBLE (-6225 3325);
FORCEPROP 1 LAST BODY_TYPE PLUMBING
J 0
(-6225 3375);
DISPLAY 0.872340 (-6225 3375);
PAINT GREEN (-6225 3375);
DISPLAY INVISIBLE (-6225 3375);
FORCEPROP 1 LAST HDL_TAP TRUE
J 0
(-5900 3200);
DISPLAY 0.872340 (-5900 3200);
DISPLAY INVISIBLE (-5900 3200);
FORCEPROP 1 LAST PATH I225
J 0
(-6227 3325);
DISPLAY 0.872340 (-6227 3325);
PAINT GREEN (-6227 3325);
DISPLAY INVISIBLE (-6227 3325);
FORCEADD TAP..1
(-6225 3575);
FORCEPROP 3 LASTPIN (-6275 3575) SIG_NAME M_C_CPU0_SB_DQ<21>
J 0
(-6265 3585);
DISPLAY 0.659574 (-6265 3585);
PAINT MONO (-6265 3585);
DISPLAY INVISIBLE (-6265 3585);
FORCEPROP 1 LASTPIN (-6275 3575) BN 21
J 0
(-6287 3583);
DISPLAY 0.489362 (-6287 3583);
PAINT GREEN (-6287 3583);
FORCEPROP 2 LAST CDS_LIB mstr_standard
J 0
(-6225 3575);
DISPLAY 0.723404 (-6225 3575);
PAINT MONO (-6225 3575);
DISPLAY INVISIBLE (-6225 3575);
FORCEPROP 1 LAST BODY_TYPE PLUMBING
J 0
(-6225 3625);
DISPLAY 0.872340 (-6225 3625);
PAINT GREEN (-6225 3625);
DISPLAY INVISIBLE (-6225 3625);
FORCEPROP 1 LAST HDL_TAP TRUE
J 0
(-5900 3450);
DISPLAY 0.872340 (-5900 3450);
DISPLAY INVISIBLE (-5900 3450);
FORCEPROP 1 LAST PATH I226
J 0
(-6227 3575);
DISPLAY 0.872340 (-6227 3575);
PAINT GREEN (-6227 3575);
DISPLAY INVISIBLE (-6227 3575);
FORCEADD TAP..1
(-6225 3625);
FORCEPROP 3 LASTPIN (-6275 3625) SIG_NAME M_C_CPU0_SB_DQ<22>
J 0
(-6265 3635);
DISPLAY 0.659574 (-6265 3635);
PAINT MONO (-6265 3635);
DISPLAY INVISIBLE (-6265 3635);
FORCEPROP 1 LASTPIN (-6275 3625) BN 22
J 0
(-6287 3633);
DISPLAY 0.489362 (-6287 3633);
PAINT GREEN (-6287 3633);
FORCEPROP 2 LAST CDS_LIB mstr_standard
J 0
(-6225 3625);
DISPLAY 0.723404 (-6225 3625);
PAINT MONO (-6225 3625);
DISPLAY INVISIBLE (-6225 3625);
FORCEPROP 1 LAST BODY_TYPE PLUMBING
J 0
(-6225 3675);
DISPLAY 0.872340 (-6225 3675);
PAINT GREEN (-6225 3675);
DISPLAY INVISIBLE (-6225 3675);
FORCEPROP 1 LAST HDL_TAP TRUE
J 0
(-5900 3500);
DISPLAY 0.872340 (-5900 3500);
DISPLAY INVISIBLE (-5900 3500);
FORCEPROP 1 LAST PATH I227
J 0
(-6227 3625);
DISPLAY 0.872340 (-6227 3625);
PAINT GREEN (-6227 3625);
DISPLAY INVISIBLE (-6227 3625);
FORCEADD TAP..1
(-6225 3525);
FORCEPROP 3 LASTPIN (-6275 3525) SIG_NAME M_C_CPU0_SB_DQ<20>
J 0
(-6265 3535);
DISPLAY 0.659574 (-6265 3535);
PAINT MONO (-6265 3535);
DISPLAY INVISIBLE (-6265 3535);
FORCEPROP 1 LASTPIN (-6275 3525) BN 20
J 0
(-6287 3533);
DISPLAY 0.489362 (-6287 3533);
PAINT GREEN (-6287 3533);
FORCEPROP 2 LAST CDS_LIB mstr_standard
J 0
(-6225 3525);
DISPLAY 0.723404 (-6225 3525);
PAINT MONO (-6225 3525);
DISPLAY INVISIBLE (-6225 3525);
FORCEPROP 1 LAST BODY_TYPE PLUMBING
J 0
(-6225 3575);
DISPLAY 0.872340 (-6225 3575);
PAINT GREEN (-6225 3575);
DISPLAY INVISIBLE (-6225 3575);
FORCEPROP 1 LAST HDL_TAP TRUE
J 0
(-5900 3400);
DISPLAY 0.872340 (-5900 3400);
DISPLAY INVISIBLE (-5900 3400);
FORCEPROP 1 LAST PATH I228
J 0
(-6227 3525);
DISPLAY 0.872340 (-6227 3525);
PAINT GREEN (-6227 3525);
DISPLAY INVISIBLE (-6227 3525);
FORCEADD TAP..1
(-6225 3675);
FORCEPROP 3 LASTPIN (-6275 3675) SIG_NAME M_C_CPU0_SB_DQ<23>
J 0
(-6265 3685);
DISPLAY 0.659574 (-6265 3685);
PAINT MONO (-6265 3685);
DISPLAY INVISIBLE (-6265 3685);
FORCEPROP 1 LASTPIN (-6275 3675) BN 23
J 0
(-6287 3683);
DISPLAY 0.489362 (-6287 3683);
PAINT GREEN (-6287 3683);
FORCEPROP 2 LAST CDS_LIB mstr_standard
J 0
(-6225 3675);
DISPLAY 0.723404 (-6225 3675);
PAINT MONO (-6225 3675);
DISPLAY INVISIBLE (-6225 3675);
FORCEPROP 1 LAST BODY_TYPE PLUMBING
J 0
(-6225 3725);
DISPLAY 0.872340 (-6225 3725);
PAINT GREEN (-6225 3725);
DISPLAY INVISIBLE (-6225 3725);
FORCEPROP 1 LAST HDL_TAP TRUE
J 0
(-5900 3550);
DISPLAY 0.872340 (-5900 3550);
DISPLAY INVISIBLE (-5900 3550);
FORCEPROP 1 LAST PATH I229
J 0
(-6227 3675);
DISPLAY 0.872340 (-6227 3675);
PAINT GREEN (-6227 3675);
DISPLAY INVISIBLE (-6227 3675);
FORCEADD TAP..1
(-6225 3475);
FORCEPROP 3 LASTPIN (-6275 3475) SIG_NAME M_C_CPU0_SB_DQ<19>
J 0
(-6265 3485);
DISPLAY 0.659574 (-6265 3485);
PAINT MONO (-6265 3485);
DISPLAY INVISIBLE (-6265 3485);
FORCEPROP 1 LASTPIN (-6275 3475) BN 19
J 0
(-6287 3483);
DISPLAY 0.489362 (-6287 3483);
PAINT GREEN (-6287 3483);
FORCEPROP 2 LAST CDS_LIB mstr_standard
J 0
(-6225 3475);
DISPLAY 0.723404 (-6225 3475);
PAINT MONO (-6225 3475);
DISPLAY INVISIBLE (-6225 3475);
FORCEPROP 1 LAST BODY_TYPE PLUMBING
J 0
(-6225 3525);
DISPLAY 0.872340 (-6225 3525);
PAINT GREEN (-6225 3525);
DISPLAY INVISIBLE (-6225 3525);
FORCEPROP 1 LAST HDL_TAP TRUE
J 0
(-5900 3350);
DISPLAY 0.872340 (-5900 3350);
DISPLAY INVISIBLE (-5900 3350);
FORCEPROP 1 LAST PATH I230
J 0
(-6227 3475);
DISPLAY 0.872340 (-6227 3475);
PAINT GREEN (-6227 3475);
DISPLAY INVISIBLE (-6227 3475);
FORCEADD TAP..1
(-6225 3825);
FORCEPROP 3 LASTPIN (-6275 3825) SIG_NAME M_C_CPU0_SB_DQ<26>
J 0
(-6265 3835);
DISPLAY 0.659574 (-6265 3835);
PAINT MONO (-6265 3835);
DISPLAY INVISIBLE (-6265 3835);
FORCEPROP 1 LASTPIN (-6275 3825) BN 26
J 0
(-6287 3833);
DISPLAY 0.489362 (-6287 3833);
PAINT GREEN (-6287 3833);
FORCEPROP 2 LAST CDS_LIB mstr_standard
J 0
(-6225 3825);
DISPLAY 0.723404 (-6225 3825);
PAINT MONO (-6225 3825);
DISPLAY INVISIBLE (-6225 3825);
FORCEPROP 1 LAST BODY_TYPE PLUMBING
J 0
(-6225 3875);
DISPLAY 0.872340 (-6225 3875);
PAINT GREEN (-6225 3875);
DISPLAY INVISIBLE (-6225 3875);
FORCEPROP 1 LAST HDL_TAP TRUE
J 0
(-5900 3700);
DISPLAY 0.872340 (-5900 3700);
DISPLAY INVISIBLE (-5900 3700);
FORCEPROP 1 LAST PATH I231
J 0
(-6227 3825);
DISPLAY 0.872340 (-6227 3825);
PAINT GREEN (-6227 3825);
DISPLAY INVISIBLE (-6227 3825);
FORCEADD TAP..1
(-6225 3875);
FORCEPROP 3 LASTPIN (-6275 3875) SIG_NAME M_C_CPU0_SB_DQ<27>
J 0
(-6265 3885);
DISPLAY 0.659574 (-6265 3885);
PAINT MONO (-6265 3885);
DISPLAY INVISIBLE (-6265 3885);
FORCEPROP 1 LASTPIN (-6275 3875) BN 27
J 0
(-6287 3883);
DISPLAY 0.489362 (-6287 3883);
PAINT GREEN (-6287 3883);
FORCEPROP 2 LAST CDS_LIB mstr_standard
J 0
(-6225 3875);
DISPLAY 0.723404 (-6225 3875);
PAINT MONO (-6225 3875);
DISPLAY INVISIBLE (-6225 3875);
FORCEPROP 1 LAST BODY_TYPE PLUMBING
J 0
(-6225 3925);
DISPLAY 0.872340 (-6225 3925);
PAINT GREEN (-6225 3925);
DISPLAY INVISIBLE (-6225 3925);
FORCEPROP 1 LAST HDL_TAP TRUE
J 0
(-5900 3750);
DISPLAY 0.872340 (-5900 3750);
DISPLAY INVISIBLE (-5900 3750);
FORCEPROP 1 LAST PATH I232
J 0
(-6227 3875);
DISPLAY 0.872340 (-6227 3875);
PAINT GREEN (-6227 3875);
DISPLAY INVISIBLE (-6227 3875);
FORCEADD TAP..1
(-6225 3775);
FORCEPROP 3 LASTPIN (-6275 3775) SIG_NAME M_C_CPU0_SB_DQ<25>
J 0
(-6265 3785);
DISPLAY 0.659574 (-6265 3785);
PAINT MONO (-6265 3785);
DISPLAY INVISIBLE (-6265 3785);
FORCEPROP 1 LASTPIN (-6275 3775) BN 25
J 0
(-6287 3783);
DISPLAY 0.489362 (-6287 3783);
PAINT GREEN (-6287 3783);
FORCEPROP 2 LAST CDS_LIB mstr_standard
J 0
(-6225 3775);
DISPLAY 0.723404 (-6225 3775);
PAINT MONO (-6225 3775);
DISPLAY INVISIBLE (-6225 3775);
FORCEPROP 1 LAST BODY_TYPE PLUMBING
J 0
(-6225 3825);
DISPLAY 0.872340 (-6225 3825);
PAINT GREEN (-6225 3825);
DISPLAY INVISIBLE (-6225 3825);
FORCEPROP 1 LAST HDL_TAP TRUE
J 0
(-5900 3650);
DISPLAY 0.872340 (-5900 3650);
DISPLAY INVISIBLE (-5900 3650);
FORCEPROP 1 LAST PATH I233
J 0
(-6227 3775);
DISPLAY 0.872340 (-6227 3775);
PAINT GREEN (-6227 3775);
DISPLAY INVISIBLE (-6227 3775);
FORCEADD TAP..1
(-6225 3925);
FORCEPROP 3 LASTPIN (-6275 3925) SIG_NAME M_C_CPU0_SB_DQ<28>
J 0
(-6265 3935);
DISPLAY 0.659574 (-6265 3935);
PAINT MONO (-6265 3935);
DISPLAY INVISIBLE (-6265 3935);
FORCEPROP 1 LASTPIN (-6275 3925) BN 28
J 0
(-6287 3933);
DISPLAY 0.489362 (-6287 3933);
PAINT GREEN (-6287 3933);
FORCEPROP 2 LAST CDS_LIB mstr_standard
J 0
(-6225 3925);
DISPLAY 0.723404 (-6225 3925);
PAINT MONO (-6225 3925);
DISPLAY INVISIBLE (-6225 3925);
FORCEPROP 1 LAST BODY_TYPE PLUMBING
J 0
(-6225 3975);
DISPLAY 0.872340 (-6225 3975);
PAINT GREEN (-6225 3975);
DISPLAY INVISIBLE (-6225 3975);
FORCEPROP 1 LAST HDL_TAP TRUE
J 0
(-5900 3800);
DISPLAY 0.872340 (-5900 3800);
DISPLAY INVISIBLE (-5900 3800);
FORCEPROP 1 LAST PATH I234
J 0
(-6227 3925);
DISPLAY 0.872340 (-6227 3925);
PAINT GREEN (-6227 3925);
DISPLAY INVISIBLE (-6227 3925);
FORCEADD TAP..1
(-6225 3725);
FORCEPROP 3 LASTPIN (-6275 3725) SIG_NAME M_C_CPU0_SB_DQ<24>
J 0
(-6265 3735);
DISPLAY 0.659574 (-6265 3735);
PAINT MONO (-6265 3735);
DISPLAY INVISIBLE (-6265 3735);
FORCEPROP 1 LASTPIN (-6275 3725) BN 24
J 0
(-6287 3733);
DISPLAY 0.489362 (-6287 3733);
PAINT GREEN (-6287 3733);
FORCEPROP 2 LAST CDS_LIB mstr_standard
J 0
(-6225 3725);
DISPLAY 0.723404 (-6225 3725);
PAINT MONO (-6225 3725);
DISPLAY INVISIBLE (-6225 3725);
FORCEPROP 1 LAST BODY_TYPE PLUMBING
J 0
(-6225 3775);
DISPLAY 0.872340 (-6225 3775);
PAINT GREEN (-6225 3775);
DISPLAY INVISIBLE (-6225 3775);
FORCEPROP 1 LAST HDL_TAP TRUE
J 0
(-5900 3600);
DISPLAY 0.872340 (-5900 3600);
DISPLAY INVISIBLE (-5900 3600);
FORCEPROP 1 LAST PATH I235
J 0
(-6227 3725);
DISPLAY 0.872340 (-6227 3725);
PAINT GREEN (-6227 3725);
DISPLAY INVISIBLE (-6227 3725);
FORCEADD TAP..1
(-6225 4175);
FORCEPROP 3 LASTPIN (-6275 4175) SIG_NAME M_C_CPU0_SA_DQ<0>
J 0
(-6265 4185);
DISPLAY 0.659574 (-6265 4185);
PAINT MONO (-6265 4185);
DISPLAY INVISIBLE (-6265 4185);
FORCEPROP 1 LASTPIN (-6275 4175) BN 0
J 0
(-6287 4183);
DISPLAY 0.489362 (-6287 4183);
PAINT GREEN (-6287 4183);
FORCEPROP 2 LAST CDS_LIB mstr_standard
J 0
(-6225 4175);
DISPLAY 0.723404 (-6225 4175);
PAINT MONO (-6225 4175);
DISPLAY INVISIBLE (-6225 4175);
FORCEPROP 1 LAST BODY_TYPE PLUMBING
J 0
(-6225 4225);
DISPLAY 0.872340 (-6225 4225);
PAINT GREEN (-6225 4225);
DISPLAY INVISIBLE (-6225 4225);
FORCEPROP 1 LAST HDL_TAP TRUE
J 0
(-5900 4050);
DISPLAY 0.872340 (-5900 4050);
DISPLAY INVISIBLE (-5900 4050);
FORCEPROP 1 LAST PATH I236
J 0
(-6227 4175);
DISPLAY 0.872340 (-6227 4175);
PAINT GREEN (-6227 4175);
DISPLAY INVISIBLE (-6227 4175);
FORCEADD TAP..1
(-6225 4025);
FORCEPROP 3 LASTPIN (-6275 4025) SIG_NAME M_C_CPU0_SB_DQ<30>
J 0
(-6265 4035);
DISPLAY 0.659574 (-6265 4035);
PAINT MONO (-6265 4035);
DISPLAY INVISIBLE (-6265 4035);
FORCEPROP 1 LASTPIN (-6275 4025) BN 30
J 0
(-6287 4033);
DISPLAY 0.489362 (-6287 4033);
PAINT GREEN (-6287 4033);
FORCEPROP 2 LAST CDS_LIB mstr_standard
J 0
(-6225 4025);
DISPLAY 0.723404 (-6225 4025);
PAINT MONO (-6225 4025);
DISPLAY INVISIBLE (-6225 4025);
FORCEPROP 1 LAST BODY_TYPE PLUMBING
J 0
(-6225 4075);
DISPLAY 0.872340 (-6225 4075);
PAINT GREEN (-6225 4075);
DISPLAY INVISIBLE (-6225 4075);
FORCEPROP 1 LAST HDL_TAP TRUE
J 0
(-5900 3900);
DISPLAY 0.872340 (-5900 3900);
DISPLAY INVISIBLE (-5900 3900);
FORCEPROP 1 LAST PATH I237
J 0
(-6227 4025);
DISPLAY 0.872340 (-6227 4025);
PAINT GREEN (-6227 4025);
DISPLAY INVISIBLE (-6227 4025);
FORCEADD TAP..1
(-6225 4075);
FORCEPROP 3 LASTPIN (-6275 4075) SIG_NAME M_C_CPU0_SB_DQ<31>
J 0
(-6265 4085);
DISPLAY 0.659574 (-6265 4085);
PAINT MONO (-6265 4085);
DISPLAY INVISIBLE (-6265 4085);
FORCEPROP 1 LASTPIN (-6275 4075) BN 31
J 0
(-6287 4083);
DISPLAY 0.489362 (-6287 4083);
PAINT GREEN (-6287 4083);
FORCEPROP 2 LAST CDS_LIB mstr_standard
J 0
(-6225 4075);
DISPLAY 0.723404 (-6225 4075);
PAINT MONO (-6225 4075);
DISPLAY INVISIBLE (-6225 4075);
FORCEPROP 1 LAST BODY_TYPE PLUMBING
J 0
(-6225 4125);
DISPLAY 0.872340 (-6225 4125);
PAINT GREEN (-6225 4125);
DISPLAY INVISIBLE (-6225 4125);
FORCEPROP 1 LAST HDL_TAP TRUE
J 0
(-5900 3950);
DISPLAY 0.872340 (-5900 3950);
DISPLAY INVISIBLE (-5900 3950);
FORCEPROP 1 LAST PATH I238
J 0
(-6227 4075);
DISPLAY 0.872340 (-6227 4075);
PAINT GREEN (-6227 4075);
DISPLAY INVISIBLE (-6227 4075);
FORCEADD TAP..1
(-6225 3975);
FORCEPROP 3 LASTPIN (-6275 3975) SIG_NAME M_C_CPU0_SB_DQ<29>
J 0
(-6265 3985);
DISPLAY 0.659574 (-6265 3985);
PAINT MONO (-6265 3985);
DISPLAY INVISIBLE (-6265 3985);
FORCEPROP 1 LASTPIN (-6275 3975) BN 29
J 0
(-6287 3983);
DISPLAY 0.489362 (-6287 3983);
PAINT GREEN (-6287 3983);
FORCEPROP 2 LAST CDS_LIB mstr_standard
J 0
(-6225 3975);
DISPLAY 0.723404 (-6225 3975);
PAINT MONO (-6225 3975);
DISPLAY INVISIBLE (-6225 3975);
FORCEPROP 1 LAST BODY_TYPE PLUMBING
J 0
(-6225 4025);
DISPLAY 0.872340 (-6225 4025);
PAINT GREEN (-6225 4025);
DISPLAY INVISIBLE (-6225 4025);
FORCEPROP 1 LAST HDL_TAP TRUE
J 0
(-5900 3850);
DISPLAY 0.872340 (-5900 3850);
DISPLAY INVISIBLE (-5900 3850);
FORCEPROP 1 LAST PATH I239
J 0
(-6227 3975);
DISPLAY 0.872340 (-6227 3975);
PAINT GREEN (-6227 3975);
DISPLAY INVISIBLE (-6227 3975);
FORCEADD TAP..1
(-6225 4275);
FORCEPROP 3 LASTPIN (-6275 4275) SIG_NAME M_C_CPU0_SA_DQ<2>
J 0
(-6265 4285);
DISPLAY 0.659574 (-6265 4285);
PAINT MONO (-6265 4285);
DISPLAY INVISIBLE (-6265 4285);
FORCEPROP 1 LASTPIN (-6275 4275) BN 2
J 0
(-6287 4283);
DISPLAY 0.489362 (-6287 4283);
PAINT GREEN (-6287 4283);
FORCEPROP 2 LAST CDS_LIB mstr_standard
J 0
(-6225 4275);
DISPLAY 0.723404 (-6225 4275);
PAINT MONO (-6225 4275);
DISPLAY INVISIBLE (-6225 4275);
FORCEPROP 1 LAST BODY_TYPE PLUMBING
J 0
(-6225 4325);
DISPLAY 0.872340 (-6225 4325);
PAINT GREEN (-6225 4325);
DISPLAY INVISIBLE (-6225 4325);
FORCEPROP 1 LAST HDL_TAP TRUE
J 0
(-5900 4150);
DISPLAY 0.872340 (-5900 4150);
DISPLAY INVISIBLE (-5900 4150);
FORCEPROP 1 LAST PATH I240
J 0
(-6227 4275);
DISPLAY 0.872340 (-6227 4275);
PAINT GREEN (-6227 4275);
DISPLAY INVISIBLE (-6227 4275);
FORCEADD TAP..1
(-6225 4225);
FORCEPROP 3 LASTPIN (-6275 4225) SIG_NAME M_C_CPU0_SA_DQ<1>
J 0
(-6265 4235);
DISPLAY 0.659574 (-6265 4235);
PAINT MONO (-6265 4235);
DISPLAY INVISIBLE (-6265 4235);
FORCEPROP 1 LASTPIN (-6275 4225) BN 1
J 0
(-6287 4233);
DISPLAY 0.489362 (-6287 4233);
PAINT GREEN (-6287 4233);
FORCEPROP 2 LAST CDS_LIB mstr_standard
J 0
(-6225 4225);
DISPLAY 0.723404 (-6225 4225);
PAINT MONO (-6225 4225);
DISPLAY INVISIBLE (-6225 4225);
FORCEPROP 1 LAST BODY_TYPE PLUMBING
J 0
(-6225 4275);
DISPLAY 0.872340 (-6225 4275);
PAINT GREEN (-6225 4275);
DISPLAY INVISIBLE (-6225 4275);
FORCEPROP 1 LAST HDL_TAP TRUE
J 0
(-5900 4100);
DISPLAY 0.872340 (-5900 4100);
DISPLAY INVISIBLE (-5900 4100);
FORCEPROP 1 LAST PATH I241
J 0
(-6227 4225);
DISPLAY 0.872340 (-6227 4225);
PAINT GREEN (-6227 4225);
DISPLAY INVISIBLE (-6227 4225);
FORCEADD TAP..1
(-6225 4325);
FORCEPROP 3 LASTPIN (-6275 4325) SIG_NAME M_C_CPU0_SA_DQ<3>
J 0
(-6265 4335);
DISPLAY 0.659574 (-6265 4335);
PAINT MONO (-6265 4335);
DISPLAY INVISIBLE (-6265 4335);
FORCEPROP 1 LASTPIN (-6275 4325) BN 3
J 0
(-6287 4333);
DISPLAY 0.489362 (-6287 4333);
PAINT GREEN (-6287 4333);
FORCEPROP 2 LAST CDS_LIB mstr_standard
J 0
(-6225 4325);
DISPLAY 0.723404 (-6225 4325);
PAINT MONO (-6225 4325);
DISPLAY INVISIBLE (-6225 4325);
FORCEPROP 1 LAST BODY_TYPE PLUMBING
J 0
(-6225 4375);
DISPLAY 0.872340 (-6225 4375);
PAINT GREEN (-6225 4375);
DISPLAY INVISIBLE (-6225 4375);
FORCEPROP 1 LAST HDL_TAP TRUE
J 0
(-5900 4200);
DISPLAY 0.872340 (-5900 4200);
DISPLAY INVISIBLE (-5900 4200);
FORCEPROP 1 LAST PATH I242
J 0
(-6227 4325);
DISPLAY 0.872340 (-6227 4325);
PAINT GREEN (-6227 4325);
DISPLAY INVISIBLE (-6227 4325);
FORCEADD TAP..1
(-6225 4375);
FORCEPROP 3 LASTPIN (-6275 4375) SIG_NAME M_C_CPU0_SA_DQ<4>
J 0
(-6265 4385);
DISPLAY 0.659574 (-6265 4385);
PAINT MONO (-6265 4385);
DISPLAY INVISIBLE (-6265 4385);
FORCEPROP 1 LASTPIN (-6275 4375) BN 4
J 0
(-6287 4383);
DISPLAY 0.489362 (-6287 4383);
PAINT GREEN (-6287 4383);
FORCEPROP 2 LAST CDS_LIB mstr_standard
J 0
(-6225 4375);
DISPLAY 0.723404 (-6225 4375);
PAINT MONO (-6225 4375);
DISPLAY INVISIBLE (-6225 4375);
FORCEPROP 1 LAST BODY_TYPE PLUMBING
J 0
(-6225 4425);
DISPLAY 0.872340 (-6225 4425);
PAINT GREEN (-6225 4425);
DISPLAY INVISIBLE (-6225 4425);
FORCEPROP 1 LAST HDL_TAP TRUE
J 0
(-5900 4250);
DISPLAY 0.872340 (-5900 4250);
DISPLAY INVISIBLE (-5900 4250);
FORCEPROP 1 LAST PATH I243
J 0
(-6227 4375);
DISPLAY 0.872340 (-6227 4375);
PAINT GREEN (-6227 4375);
DISPLAY INVISIBLE (-6227 4375);
FORCEADD TAP..1
(-6225 4425);
FORCEPROP 3 LASTPIN (-6275 4425) SIG_NAME M_C_CPU0_SA_DQ<5>
J 0
(-6265 4435);
DISPLAY 0.659574 (-6265 4435);
PAINT MONO (-6265 4435);
DISPLAY INVISIBLE (-6265 4435);
FORCEPROP 1 LASTPIN (-6275 4425) BN 5
J 0
(-6287 4433);
DISPLAY 0.489362 (-6287 4433);
PAINT GREEN (-6287 4433);
FORCEPROP 2 LAST CDS_LIB mstr_standard
J 0
(-6225 4425);
DISPLAY 0.723404 (-6225 4425);
PAINT MONO (-6225 4425);
DISPLAY INVISIBLE (-6225 4425);
FORCEPROP 1 LAST BODY_TYPE PLUMBING
J 0
(-6225 4475);
DISPLAY 0.872340 (-6225 4475);
PAINT GREEN (-6225 4475);
DISPLAY INVISIBLE (-6225 4475);
FORCEPROP 1 LAST HDL_TAP TRUE
J 0
(-5900 4300);
DISPLAY 0.872340 (-5900 4300);
DISPLAY INVISIBLE (-5900 4300);
FORCEPROP 1 LAST PATH I244
J 0
(-6227 4425);
DISPLAY 0.872340 (-6227 4425);
PAINT GREEN (-6227 4425);
DISPLAY INVISIBLE (-6227 4425);
FORCEADD TAP..1
(-6225 4525);
FORCEPROP 3 LASTPIN (-6275 4525) SIG_NAME M_C_CPU0_SA_DQ<7>
J 0
(-6265 4535);
DISPLAY 0.659574 (-6265 4535);
PAINT MONO (-6265 4535);
DISPLAY INVISIBLE (-6265 4535);
FORCEPROP 1 LASTPIN (-6275 4525) BN 7
J 0
(-6287 4533);
DISPLAY 0.489362 (-6287 4533);
PAINT GREEN (-6287 4533);
FORCEPROP 2 LAST CDS_LIB mstr_standard
J 0
(-6225 4525);
DISPLAY 0.723404 (-6225 4525);
PAINT MONO (-6225 4525);
DISPLAY INVISIBLE (-6225 4525);
FORCEPROP 1 LAST BODY_TYPE PLUMBING
J 0
(-6225 4575);
DISPLAY 0.872340 (-6225 4575);
PAINT GREEN (-6225 4575);
DISPLAY INVISIBLE (-6225 4575);
FORCEPROP 1 LAST HDL_TAP TRUE
J 0
(-5900 4400);
DISPLAY 0.872340 (-5900 4400);
DISPLAY INVISIBLE (-5900 4400);
FORCEPROP 1 LAST PATH I245
J 0
(-6227 4525);
DISPLAY 0.872340 (-6227 4525);
PAINT GREEN (-6227 4525);
DISPLAY INVISIBLE (-6227 4525);
FORCEADD TAP..1
(-6225 4475);
FORCEPROP 3 LASTPIN (-6275 4475) SIG_NAME M_C_CPU0_SA_DQ<6>
J 0
(-6265 4485);
DISPLAY 0.659574 (-6265 4485);
PAINT MONO (-6265 4485);
DISPLAY INVISIBLE (-6265 4485);
FORCEPROP 1 LASTPIN (-6275 4475) BN 6
J 0
(-6287 4483);
DISPLAY 0.489362 (-6287 4483);
PAINT GREEN (-6287 4483);
FORCEPROP 2 LAST CDS_LIB mstr_standard
J 0
(-6225 4475);
DISPLAY 0.723404 (-6225 4475);
PAINT MONO (-6225 4475);
DISPLAY INVISIBLE (-6225 4475);
FORCEPROP 1 LAST BODY_TYPE PLUMBING
J 0
(-6225 4525);
DISPLAY 0.872340 (-6225 4525);
PAINT GREEN (-6225 4525);
DISPLAY INVISIBLE (-6225 4525);
FORCEPROP 1 LAST HDL_TAP TRUE
J 0
(-5900 4350);
DISPLAY 0.872340 (-5900 4350);
DISPLAY INVISIBLE (-5900 4350);
FORCEPROP 1 LAST PATH I246
J 0
(-6227 4475);
DISPLAY 0.872340 (-6227 4475);
PAINT GREEN (-6227 4475);
DISPLAY INVISIBLE (-6227 4475);
FORCEADD TAP..1
(-6225 4575);
FORCEPROP 3 LASTPIN (-6275 4575) SIG_NAME M_C_CPU0_SA_DQ<8>
J 0
(-6265 4585);
DISPLAY 0.659574 (-6265 4585);
PAINT MONO (-6265 4585);
DISPLAY INVISIBLE (-6265 4585);
FORCEPROP 1 LASTPIN (-6275 4575) BN 8
J 0
(-6287 4583);
DISPLAY 0.489362 (-6287 4583);
PAINT GREEN (-6287 4583);
FORCEPROP 2 LAST CDS_LIB mstr_standard
J 0
(-6225 4575);
DISPLAY 0.723404 (-6225 4575);
PAINT MONO (-6225 4575);
DISPLAY INVISIBLE (-6225 4575);
FORCEPROP 1 LAST BODY_TYPE PLUMBING
J 0
(-6225 4625);
DISPLAY 0.872340 (-6225 4625);
PAINT GREEN (-6225 4625);
DISPLAY INVISIBLE (-6225 4625);
FORCEPROP 1 LAST HDL_TAP TRUE
J 0
(-5900 4450);
DISPLAY 0.872340 (-5900 4450);
DISPLAY INVISIBLE (-5900 4450);
FORCEPROP 1 LAST PATH I247
J 0
(-6227 4575);
DISPLAY 0.872340 (-6227 4575);
PAINT GREEN (-6227 4575);
DISPLAY INVISIBLE (-6227 4575);
FORCEADD TAP..1
(-6225 4625);
FORCEPROP 3 LASTPIN (-6275 4625) SIG_NAME M_C_CPU0_SA_DQ<9>
J 0
(-6265 4635);
DISPLAY 0.659574 (-6265 4635);
PAINT MONO (-6265 4635);
DISPLAY INVISIBLE (-6265 4635);
FORCEPROP 1 LASTPIN (-6275 4625) BN 9
J 0
(-6287 4633);
DISPLAY 0.489362 (-6287 4633);
PAINT GREEN (-6287 4633);
FORCEPROP 2 LAST CDS_LIB mstr_standard
J 0
(-6225 4625);
DISPLAY 0.723404 (-6225 4625);
PAINT MONO (-6225 4625);
DISPLAY INVISIBLE (-6225 4625);
FORCEPROP 1 LAST BODY_TYPE PLUMBING
J 0
(-6225 4675);
DISPLAY 0.872340 (-6225 4675);
PAINT GREEN (-6225 4675);
DISPLAY INVISIBLE (-6225 4675);
FORCEPROP 1 LAST HDL_TAP TRUE
J 0
(-5900 4500);
DISPLAY 0.872340 (-5900 4500);
DISPLAY INVISIBLE (-5900 4500);
FORCEPROP 1 LAST PATH I248
J 0
(-6227 4625);
DISPLAY 0.872340 (-6227 4625);
PAINT GREEN (-6227 4625);
DISPLAY INVISIBLE (-6227 4625);
FORCEADD TAP..1
(-6225 4675);
FORCEPROP 3 LASTPIN (-6275 4675) SIG_NAME M_C_CPU0_SA_DQ<10>
J 0
(-6265 4685);
DISPLAY 0.659574 (-6265 4685);
PAINT MONO (-6265 4685);
DISPLAY INVISIBLE (-6265 4685);
FORCEPROP 1 LASTPIN (-6275 4675) BN 10
J 0
(-6287 4683);
DISPLAY 0.489362 (-6287 4683);
PAINT GREEN (-6287 4683);
FORCEPROP 2 LAST CDS_LIB mstr_standard
J 0
(-6225 4675);
DISPLAY 0.723404 (-6225 4675);
PAINT MONO (-6225 4675);
DISPLAY INVISIBLE (-6225 4675);
FORCEPROP 1 LAST BODY_TYPE PLUMBING
J 0
(-6225 4725);
DISPLAY 0.872340 (-6225 4725);
PAINT GREEN (-6225 4725);
DISPLAY INVISIBLE (-6225 4725);
FORCEPROP 1 LAST HDL_TAP TRUE
J 0
(-5900 4550);
DISPLAY 0.872340 (-5900 4550);
DISPLAY INVISIBLE (-5900 4550);
FORCEPROP 1 LAST PATH I249
J 0
(-6227 4675);
DISPLAY 0.872340 (-6227 4675);
PAINT GREEN (-6227 4675);
DISPLAY INVISIBLE (-6227 4675);
FORCEADD TAP..1
(-6225 4875);
FORCEPROP 3 LASTPIN (-6275 4875) SIG_NAME M_C_CPU0_SA_DQ<14>
J 0
(-6265 4885);
DISPLAY 0.659574 (-6265 4885);
PAINT MONO (-6265 4885);
DISPLAY INVISIBLE (-6265 4885);
FORCEPROP 1 LASTPIN (-6275 4875) BN 14
J 0
(-6287 4883);
DISPLAY 0.489362 (-6287 4883);
PAINT GREEN (-6287 4883);
FORCEPROP 2 LAST CDS_LIB mstr_standard
J 0
(-6225 4875);
DISPLAY 0.723404 (-6225 4875);
PAINT MONO (-6225 4875);
DISPLAY INVISIBLE (-6225 4875);
FORCEPROP 1 LAST BODY_TYPE PLUMBING
J 0
(-6225 4925);
DISPLAY 0.872340 (-6225 4925);
PAINT GREEN (-6225 4925);
DISPLAY INVISIBLE (-6225 4925);
FORCEPROP 1 LAST HDL_TAP TRUE
J 0
(-5900 4750);
DISPLAY 0.872340 (-5900 4750);
DISPLAY INVISIBLE (-5900 4750);
FORCEPROP 1 LAST PATH I250
J 0
(-6227 4875);
DISPLAY 0.872340 (-6227 4875);
PAINT GREEN (-6227 4875);
DISPLAY INVISIBLE (-6227 4875);
FORCEADD TAP..1
(-6225 4925);
FORCEPROP 3 LASTPIN (-6275 4925) SIG_NAME M_C_CPU0_SA_DQ<15>
J 0
(-6265 4935);
DISPLAY 0.659574 (-6265 4935);
PAINT MONO (-6265 4935);
DISPLAY INVISIBLE (-6265 4935);
FORCEPROP 1 LASTPIN (-6275 4925) BN 15
J 0
(-6287 4933);
DISPLAY 0.489362 (-6287 4933);
PAINT GREEN (-6287 4933);
FORCEPROP 2 LAST CDS_LIB mstr_standard
J 0
(-6225 4925);
DISPLAY 0.723404 (-6225 4925);
PAINT MONO (-6225 4925);
DISPLAY INVISIBLE (-6225 4925);
FORCEPROP 1 LAST BODY_TYPE PLUMBING
J 0
(-6225 4975);
DISPLAY 0.872340 (-6225 4975);
PAINT GREEN (-6225 4975);
DISPLAY INVISIBLE (-6225 4975);
FORCEPROP 1 LAST HDL_TAP TRUE
J 0
(-5900 4800);
DISPLAY 0.872340 (-5900 4800);
DISPLAY INVISIBLE (-5900 4800);
FORCEPROP 1 LAST PATH I251
J 0
(-6227 4925);
DISPLAY 0.872340 (-6227 4925);
PAINT GREEN (-6227 4925);
DISPLAY INVISIBLE (-6227 4925);
FORCEADD TAP..1
(-6225 4825);
FORCEPROP 3 LASTPIN (-6275 4825) SIG_NAME M_C_CPU0_SA_DQ<13>
J 0
(-6265 4835);
DISPLAY 0.659574 (-6265 4835);
PAINT MONO (-6265 4835);
DISPLAY INVISIBLE (-6265 4835);
FORCEPROP 1 LASTPIN (-6275 4825) BN 13
J 0
(-6287 4833);
DISPLAY 0.489362 (-6287 4833);
PAINT GREEN (-6287 4833);
FORCEPROP 2 LAST CDS_LIB mstr_standard
J 0
(-6225 4825);
DISPLAY 0.723404 (-6225 4825);
PAINT MONO (-6225 4825);
DISPLAY INVISIBLE (-6225 4825);
FORCEPROP 1 LAST BODY_TYPE PLUMBING
J 0
(-6225 4875);
DISPLAY 0.872340 (-6225 4875);
PAINT GREEN (-6225 4875);
DISPLAY INVISIBLE (-6225 4875);
FORCEPROP 1 LAST HDL_TAP TRUE
J 0
(-5900 4700);
DISPLAY 0.872340 (-5900 4700);
DISPLAY INVISIBLE (-5900 4700);
FORCEPROP 1 LAST PATH I252
J 0
(-6227 4825);
DISPLAY 0.872340 (-6227 4825);
PAINT GREEN (-6227 4825);
DISPLAY INVISIBLE (-6227 4825);
FORCEADD TAP..1
(-6225 4775);
FORCEPROP 3 LASTPIN (-6275 4775) SIG_NAME M_C_CPU0_SA_DQ<12>
J 0
(-6265 4785);
DISPLAY 0.659574 (-6265 4785);
PAINT MONO (-6265 4785);
DISPLAY INVISIBLE (-6265 4785);
FORCEPROP 1 LASTPIN (-6275 4775) BN 12
J 0
(-6287 4783);
DISPLAY 0.489362 (-6287 4783);
PAINT GREEN (-6287 4783);
FORCEPROP 2 LAST CDS_LIB mstr_standard
J 0
(-6225 4775);
DISPLAY 0.723404 (-6225 4775);
PAINT MONO (-6225 4775);
DISPLAY INVISIBLE (-6225 4775);
FORCEPROP 1 LAST BODY_TYPE PLUMBING
J 0
(-6225 4825);
DISPLAY 0.872340 (-6225 4825);
PAINT GREEN (-6225 4825);
DISPLAY INVISIBLE (-6225 4825);
FORCEPROP 1 LAST HDL_TAP TRUE
J 0
(-5900 4650);
DISPLAY 0.872340 (-5900 4650);
DISPLAY INVISIBLE (-5900 4650);
FORCEPROP 1 LAST PATH I253
J 0
(-6227 4775);
DISPLAY 0.872340 (-6227 4775);
PAINT GREEN (-6227 4775);
DISPLAY INVISIBLE (-6227 4775);
FORCEADD TAP..1
(-6225 4725);
FORCEPROP 3 LASTPIN (-6275 4725) SIG_NAME M_C_CPU0_SA_DQ<11>
J 0
(-6265 4735);
DISPLAY 0.659574 (-6265 4735);
PAINT MONO (-6265 4735);
DISPLAY INVISIBLE (-6265 4735);
FORCEPROP 1 LASTPIN (-6275 4725) BN 11
J 0
(-6287 4733);
DISPLAY 0.489362 (-6287 4733);
PAINT GREEN (-6287 4733);
FORCEPROP 2 LAST CDS_LIB mstr_standard
J 0
(-6225 4725);
DISPLAY 0.723404 (-6225 4725);
PAINT MONO (-6225 4725);
DISPLAY INVISIBLE (-6225 4725);
FORCEPROP 1 LAST BODY_TYPE PLUMBING
J 0
(-6225 4775);
DISPLAY 0.872340 (-6225 4775);
PAINT GREEN (-6225 4775);
DISPLAY INVISIBLE (-6225 4775);
FORCEPROP 1 LAST HDL_TAP TRUE
J 0
(-5900 4600);
DISPLAY 0.872340 (-5900 4600);
DISPLAY INVISIBLE (-5900 4600);
FORCEPROP 1 LAST PATH I254
J 0
(-6227 4725);
DISPLAY 0.872340 (-6227 4725);
PAINT GREEN (-6227 4725);
DISPLAY INVISIBLE (-6227 4725);
FORCEADD TAP..1
(-6225 5025);
FORCEPROP 3 LASTPIN (-6275 5025) SIG_NAME M_C_CPU0_SA_DQ<17>
J 0
(-6265 5035);
DISPLAY 0.659574 (-6265 5035);
PAINT MONO (-6265 5035);
DISPLAY INVISIBLE (-6265 5035);
FORCEPROP 1 LASTPIN (-6275 5025) BN 17
J 0
(-6287 5033);
DISPLAY 0.489362 (-6287 5033);
PAINT GREEN (-6287 5033);
FORCEPROP 2 LAST CDS_LIB mstr_standard
J 0
(-6225 5025);
DISPLAY 0.723404 (-6225 5025);
PAINT MONO (-6225 5025);
DISPLAY INVISIBLE (-6225 5025);
FORCEPROP 1 LAST BODY_TYPE PLUMBING
J 0
(-6225 5075);
DISPLAY 0.872340 (-6225 5075);
PAINT GREEN (-6225 5075);
DISPLAY INVISIBLE (-6225 5075);
FORCEPROP 1 LAST HDL_TAP TRUE
J 0
(-5900 4900);
DISPLAY 0.872340 (-5900 4900);
DISPLAY INVISIBLE (-5900 4900);
FORCEPROP 1 LAST PATH I255
J 0
(-6227 5025);
DISPLAY 0.872340 (-6227 5025);
PAINT GREEN (-6227 5025);
DISPLAY INVISIBLE (-6227 5025);
FORCEADD TAP..1
(-6225 5075);
FORCEPROP 3 LASTPIN (-6275 5075) SIG_NAME M_C_CPU0_SA_DQ<18>
J 0
(-6265 5085);
DISPLAY 0.659574 (-6265 5085);
PAINT MONO (-6265 5085);
DISPLAY INVISIBLE (-6265 5085);
FORCEPROP 1 LASTPIN (-6275 5075) BN 18
J 0
(-6287 5083);
DISPLAY 0.489362 (-6287 5083);
PAINT GREEN (-6287 5083);
FORCEPROP 2 LAST CDS_LIB mstr_standard
J 0
(-6225 5075);
DISPLAY 0.723404 (-6225 5075);
PAINT MONO (-6225 5075);
DISPLAY INVISIBLE (-6225 5075);
FORCEPROP 1 LAST BODY_TYPE PLUMBING
J 0
(-6225 5125);
DISPLAY 0.872340 (-6225 5125);
PAINT GREEN (-6225 5125);
DISPLAY INVISIBLE (-6225 5125);
FORCEPROP 1 LAST HDL_TAP TRUE
J 0
(-5900 4950);
DISPLAY 0.872340 (-5900 4950);
DISPLAY INVISIBLE (-5900 4950);
FORCEPROP 1 LAST PATH I256
J 0
(-6227 5075);
DISPLAY 0.872340 (-6227 5075);
PAINT GREEN (-6227 5075);
DISPLAY INVISIBLE (-6227 5075);
FORCEADD TAP..1
(-6225 4975);
FORCEPROP 3 LASTPIN (-6275 4975) SIG_NAME M_C_CPU0_SA_DQ<16>
J 0
(-6265 4985);
DISPLAY 0.659574 (-6265 4985);
PAINT MONO (-6265 4985);
DISPLAY INVISIBLE (-6265 4985);
FORCEPROP 1 LASTPIN (-6275 4975) BN 16
J 0
(-6287 4983);
DISPLAY 0.489362 (-6287 4983);
PAINT GREEN (-6287 4983);
FORCEPROP 2 LAST CDS_LIB mstr_standard
J 0
(-6225 4975);
DISPLAY 0.723404 (-6225 4975);
PAINT MONO (-6225 4975);
DISPLAY INVISIBLE (-6225 4975);
FORCEPROP 1 LAST BODY_TYPE PLUMBING
J 0
(-6225 5025);
DISPLAY 0.872340 (-6225 5025);
PAINT GREEN (-6225 5025);
DISPLAY INVISIBLE (-6225 5025);
FORCEPROP 1 LAST HDL_TAP TRUE
J 0
(-5900 4850);
DISPLAY 0.872340 (-5900 4850);
DISPLAY INVISIBLE (-5900 4850);
FORCEPROP 1 LAST PATH I257
J 0
(-6227 4975);
DISPLAY 0.872340 (-6227 4975);
PAINT GREEN (-6227 4975);
DISPLAY INVISIBLE (-6227 4975);
FORCEADD TAP..1
(-6225 5175);
FORCEPROP 3 LASTPIN (-6275 5175) SIG_NAME M_C_CPU0_SA_DQ<20>
J 0
(-6265 5185);
DISPLAY 0.659574 (-6265 5185);
PAINT MONO (-6265 5185);
DISPLAY INVISIBLE (-6265 5185);
FORCEPROP 1 LASTPIN (-6275 5175) BN 20
J 0
(-6287 5183);
DISPLAY 0.489362 (-6287 5183);
PAINT GREEN (-6287 5183);
FORCEPROP 2 LAST CDS_LIB mstr_standard
J 0
(-6225 5175);
DISPLAY 0.723404 (-6225 5175);
PAINT MONO (-6225 5175);
DISPLAY INVISIBLE (-6225 5175);
FORCEPROP 1 LAST BODY_TYPE PLUMBING
J 0
(-6225 5225);
DISPLAY 0.872340 (-6225 5225);
PAINT GREEN (-6225 5225);
DISPLAY INVISIBLE (-6225 5225);
FORCEPROP 1 LAST HDL_TAP TRUE
J 0
(-5900 5050);
DISPLAY 0.872340 (-5900 5050);
DISPLAY INVISIBLE (-5900 5050);
FORCEPROP 1 LAST PATH I258
J 0
(-6227 5175);
DISPLAY 0.872340 (-6227 5175);
PAINT GREEN (-6227 5175);
DISPLAY INVISIBLE (-6227 5175);
FORCEADD TAP..1
(-6225 5125);
FORCEPROP 3 LASTPIN (-6275 5125) SIG_NAME M_C_CPU0_SA_DQ<19>
J 0
(-6265 5135);
DISPLAY 0.659574 (-6265 5135);
PAINT MONO (-6265 5135);
DISPLAY INVISIBLE (-6265 5135);
FORCEPROP 1 LASTPIN (-6275 5125) BN 19
J 0
(-6287 5133);
DISPLAY 0.489362 (-6287 5133);
PAINT GREEN (-6287 5133);
FORCEPROP 2 LAST CDS_LIB mstr_standard
J 0
(-6225 5125);
DISPLAY 0.723404 (-6225 5125);
PAINT MONO (-6225 5125);
DISPLAY INVISIBLE (-6225 5125);
FORCEPROP 1 LAST BODY_TYPE PLUMBING
J 0
(-6225 5175);
DISPLAY 0.872340 (-6225 5175);
PAINT GREEN (-6225 5175);
DISPLAY INVISIBLE (-6225 5175);
FORCEPROP 1 LAST HDL_TAP TRUE
J 0
(-5900 5000);
DISPLAY 0.872340 (-5900 5000);
DISPLAY INVISIBLE (-5900 5000);
FORCEPROP 1 LAST PATH I259
J 0
(-6227 5125);
DISPLAY 0.872340 (-6227 5125);
PAINT GREEN (-6227 5125);
DISPLAY INVISIBLE (-6227 5125);
FORCEADD OFFPAGE..3
(-5675 4125);
FORCEPROP 2 LAST $XR0 12 
J 0
(-5461 4125);
DISPLAY 0.638298 (-5461 4125);
PAINT MONO (-5461 4125);
FORCEPROP 2 LAST CDS_LIB mstr_standard
J 0
(-5675 4125);
DISPLAY 0.723404 (-5675 4125);
PAINT MONO (-5675 4125);
DISPLAY INVISIBLE (-5675 4125);
FORCEPROP 1 LAST OFFPAGE TRUE
J 0
(-5350 4000);
DISPLAY 0.872340 (-5350 4000);
PAINT GREEN (-5350 4000);
DISPLAY INVISIBLE (-5350 4000);
FORCEPROP 1 LAST COMMENT_BODY TRUE
J 0
(-5725 4025);
DISPLAY 0.872340 (-5725 4025);
PAINT GREEN (-5725 4025);
DISPLAY INVISIBLE (-5725 4025);
FORCEPROP 2 LAST PATH I260
J 0
(-5350 4175);
DISPLAY 0.808511 (-5350 4175);
DISPLAY INVISIBLE (-5350 4175);
FORCEADD OFFPAGE..1
(-8525 5375);
FORCEPROP 2 LAST $XR0 12 
J 0
(-8746 5375);
DISPLAY 0.638298 (-8746 5375);
PAINT MONO (-8746 5375);
FORCEPROP 2 LAST CDS_LIB mstr_standard
J 0
(-8525 5375);
DISPLAY 0.723404 (-8525 5375);
PAINT MONO (-8525 5375);
DISPLAY INVISIBLE (-8525 5375);
FORCEPROP 1 LAST OFFPAGE TRUE
J 0
(-8200 5250);
DISPLAY 0.872340 (-8200 5250);
PAINT GREEN (-8200 5250);
DISPLAY INVISIBLE (-8200 5250);
FORCEPROP 1 LAST COMMENT_BODY TRUE
J 0
(-8400 5275);
DISPLAY 0.872340 (-8400 5275);
PAINT GREEN (-8400 5275);
DISPLAY INVISIBLE (-8400 5275);
FORCEPROP 2 LAST PATH I261
J 0
(-8475 5450);
DISPLAY 0.808511 (-8475 5450);
DISPLAY INVISIBLE (-8475 5450);
FORCEADD OFFPAGE..1
(-8525 5775);
FORCEPROP 2 LAST $XR0 12 
J 0
(-8746 5775);
DISPLAY 0.638298 (-8746 5775);
PAINT MONO (-8746 5775);
FORCEPROP 2 LAST CDS_LIB mstr_standard
J 0
(-8525 5775);
DISPLAY 0.723404 (-8525 5775);
PAINT MONO (-8525 5775);
DISPLAY INVISIBLE (-8525 5775);
FORCEPROP 1 LAST OFFPAGE TRUE
J 0
(-8200 5650);
DISPLAY 0.872340 (-8200 5650);
PAINT GREEN (-8200 5650);
DISPLAY INVISIBLE (-8200 5650);
FORCEPROP 1 LAST COMMENT_BODY TRUE
J 0
(-8400 5675);
DISPLAY 0.872340 (-8400 5675);
PAINT GREEN (-8400 5675);
DISPLAY INVISIBLE (-8400 5675);
FORCEPROP 2 LAST PATH I262
J 0
(-8475 5850);
DISPLAY 0.808511 (-8475 5850);
DISPLAY INVISIBLE (-8475 5850);
FORCEADD TAP..1
R 2
(-7925 5325);
FORCEPROP 3 LASTPIN (-7875 5325) SIG_NAME M_C_CPU0_SB_CA<6>
J 0
(-7865 5335);
DISPLAY 0.659574 (-7865 5335);
PAINT MONO (-7865 5335);
DISPLAY INVISIBLE (-7865 5335);
FORCEPROP 1 LASTPIN (-7875 5325) BN 6
J 2
(-7863 5333);
DISPLAY 0.489362 (-7863 5333);
PAINT GREEN (-7863 5333);
FORCEPROP 2 LAST CDS_LIB mstr_standard
J 0
(-7925 5325);
DISPLAY 0.723404 (-7925 5325);
PAINT MONO (-7925 5325);
DISPLAY INVISIBLE (-7925 5325);
FORCEPROP 1 LAST BODY_TYPE PLUMBING
J 2
(-7925 5375);
DISPLAY 0.872340 (-7925 5375);
PAINT GREEN (-7925 5375);
DISPLAY INVISIBLE (-7925 5375);
FORCEPROP 1 LAST HDL_TAP TRUE
J 2
(-8250 5200);
DISPLAY 0.872340 (-8250 5200);
DISPLAY INVISIBLE (-8250 5200);
FORCEPROP 1 LAST PATH I263
J 2
(-7923 5325);
DISPLAY 0.872340 (-7923 5325);
PAINT GREEN (-7923 5325);
DISPLAY INVISIBLE (-7923 5325);
FORCEADD TAP..1
R 2
(-7925 5225);
FORCEPROP 3 LASTPIN (-7875 5225) SIG_NAME M_C_CPU0_SB_CA<4>
J 0
(-7865 5235);
DISPLAY 0.659574 (-7865 5235);
PAINT MONO (-7865 5235);
DISPLAY INVISIBLE (-7865 5235);
FORCEPROP 1 LASTPIN (-7875 5225) BN 4
J 2
(-7863 5233);
DISPLAY 0.489362 (-7863 5233);
PAINT GREEN (-7863 5233);
FORCEPROP 2 LAST CDS_LIB mstr_standard
J 0
(-7925 5225);
DISPLAY 0.723404 (-7925 5225);
PAINT MONO (-7925 5225);
DISPLAY INVISIBLE (-7925 5225);
FORCEPROP 1 LAST BODY_TYPE PLUMBING
J 2
(-7925 5275);
DISPLAY 0.872340 (-7925 5275);
PAINT GREEN (-7925 5275);
DISPLAY INVISIBLE (-7925 5275);
FORCEPROP 1 LAST HDL_TAP TRUE
J 2
(-8250 5100);
DISPLAY 0.872340 (-8250 5100);
DISPLAY INVISIBLE (-8250 5100);
FORCEPROP 1 LAST PATH I264
J 2
(-7923 5225);
DISPLAY 0.872340 (-7923 5225);
PAINT GREEN (-7923 5225);
DISPLAY INVISIBLE (-7923 5225);
FORCEADD TAP..1
R 2
(-7925 5275);
FORCEPROP 3 LASTPIN (-7875 5275) SIG_NAME M_C_CPU0_SB_CA<5>
J 0
(-7865 5285);
DISPLAY 0.659574 (-7865 5285);
PAINT MONO (-7865 5285);
DISPLAY INVISIBLE (-7865 5285);
FORCEPROP 1 LASTPIN (-7875 5275) BN 5
J 2
(-7863 5283);
DISPLAY 0.489362 (-7863 5283);
PAINT GREEN (-7863 5283);
FORCEPROP 2 LAST CDS_LIB mstr_standard
J 0
(-7925 5275);
DISPLAY 0.723404 (-7925 5275);
PAINT MONO (-7925 5275);
DISPLAY INVISIBLE (-7925 5275);
FORCEPROP 1 LAST BODY_TYPE PLUMBING
J 2
(-7925 5325);
DISPLAY 0.872340 (-7925 5325);
PAINT GREEN (-7925 5325);
DISPLAY INVISIBLE (-7925 5325);
FORCEPROP 1 LAST HDL_TAP TRUE
J 2
(-8250 5150);
DISPLAY 0.872340 (-8250 5150);
DISPLAY INVISIBLE (-8250 5150);
FORCEPROP 1 LAST PATH I265
J 2
(-7923 5275);
DISPLAY 0.872340 (-7923 5275);
PAINT GREEN (-7923 5275);
DISPLAY INVISIBLE (-7923 5275);
FORCEADD TAP..1
R 2
(-7925 5425);
FORCEPROP 3 LASTPIN (-7875 5425) SIG_NAME M_C_CPU0_SA_CA<0>
J 0
(-7865 5435);
DISPLAY 0.659574 (-7865 5435);
PAINT MONO (-7865 5435);
DISPLAY INVISIBLE (-7865 5435);
FORCEPROP 1 LASTPIN (-7875 5425) BN 0
J 2
(-7863 5433);
DISPLAY 0.489362 (-7863 5433);
PAINT GREEN (-7863 5433);
FORCEPROP 2 LAST CDS_LIB mstr_standard
J 0
(-7925 5425);
DISPLAY 0.723404 (-7925 5425);
PAINT MONO (-7925 5425);
DISPLAY INVISIBLE (-7925 5425);
FORCEPROP 1 LAST BODY_TYPE PLUMBING
J 2
(-7925 5475);
DISPLAY 0.872340 (-7925 5475);
PAINT GREEN (-7925 5475);
DISPLAY INVISIBLE (-7925 5475);
FORCEPROP 1 LAST HDL_TAP TRUE
J 2
(-8250 5300);
DISPLAY 0.872340 (-8250 5300);
DISPLAY INVISIBLE (-8250 5300);
FORCEPROP 1 LAST PATH I266
J 2
(-7923 5425);
DISPLAY 0.872340 (-7923 5425);
PAINT GREEN (-7923 5425);
DISPLAY INVISIBLE (-7923 5425);
FORCEADD TAP..1
R 2
(-7925 5475);
FORCEPROP 3 LASTPIN (-7875 5475) SIG_NAME M_C_CPU0_SA_CA<1>
J 0
(-7865 5485);
DISPLAY 0.659574 (-7865 5485);
PAINT MONO (-7865 5485);
DISPLAY INVISIBLE (-7865 5485);
FORCEPROP 1 LASTPIN (-7875 5475) BN 1
J 2
(-7863 5483);
DISPLAY 0.489362 (-7863 5483);
PAINT GREEN (-7863 5483);
FORCEPROP 2 LAST CDS_LIB mstr_standard
J 0
(-7925 5475);
DISPLAY 0.723404 (-7925 5475);
PAINT MONO (-7925 5475);
DISPLAY INVISIBLE (-7925 5475);
FORCEPROP 1 LAST BODY_TYPE PLUMBING
J 2
(-7925 5525);
DISPLAY 0.872340 (-7925 5525);
PAINT GREEN (-7925 5525);
DISPLAY INVISIBLE (-7925 5525);
FORCEPROP 1 LAST HDL_TAP TRUE
J 2
(-8250 5350);
DISPLAY 0.872340 (-8250 5350);
DISPLAY INVISIBLE (-8250 5350);
FORCEPROP 1 LAST PATH I267
J 2
(-7923 5475);
DISPLAY 0.872340 (-7923 5475);
PAINT GREEN (-7923 5475);
DISPLAY INVISIBLE (-7923 5475);
FORCEADD TAP..1
R 2
(-7925 5525);
FORCEPROP 3 LASTPIN (-7875 5525) SIG_NAME M_C_CPU0_SA_CA<2>
J 0
(-7865 5535);
DISPLAY 0.659574 (-7865 5535);
PAINT MONO (-7865 5535);
DISPLAY INVISIBLE (-7865 5535);
FORCEPROP 1 LASTPIN (-7875 5525) BN 2
J 2
(-7863 5533);
DISPLAY 0.489362 (-7863 5533);
PAINT GREEN (-7863 5533);
FORCEPROP 2 LAST CDS_LIB mstr_standard
J 0
(-7925 5525);
DISPLAY 0.723404 (-7925 5525);
PAINT MONO (-7925 5525);
DISPLAY INVISIBLE (-7925 5525);
FORCEPROP 1 LAST BODY_TYPE PLUMBING
J 2
(-7925 5575);
DISPLAY 0.872340 (-7925 5575);
PAINT GREEN (-7925 5575);
DISPLAY INVISIBLE (-7925 5575);
FORCEPROP 1 LAST HDL_TAP TRUE
J 2
(-8250 5400);
DISPLAY 0.872340 (-8250 5400);
DISPLAY INVISIBLE (-8250 5400);
FORCEPROP 1 LAST PATH I268
J 2
(-7923 5525);
DISPLAY 0.872340 (-7923 5525);
PAINT GREEN (-7923 5525);
DISPLAY INVISIBLE (-7923 5525);
FORCEADD TAP..1
R 2
(-7925 5575);
FORCEPROP 3 LASTPIN (-7875 5575) SIG_NAME M_C_CPU0_SA_CA<3>
J 0
(-7865 5585);
DISPLAY 0.659574 (-7865 5585);
PAINT MONO (-7865 5585);
DISPLAY INVISIBLE (-7865 5585);
FORCEPROP 1 LASTPIN (-7875 5575) BN 3
J 2
(-7863 5583);
DISPLAY 0.489362 (-7863 5583);
PAINT GREEN (-7863 5583);
FORCEPROP 2 LAST CDS_LIB mstr_standard
J 0
(-7925 5575);
DISPLAY 0.723404 (-7925 5575);
PAINT MONO (-7925 5575);
DISPLAY INVISIBLE (-7925 5575);
FORCEPROP 1 LAST BODY_TYPE PLUMBING
J 2
(-7925 5625);
DISPLAY 0.872340 (-7925 5625);
PAINT GREEN (-7925 5625);
DISPLAY INVISIBLE (-7925 5625);
FORCEPROP 1 LAST HDL_TAP TRUE
J 2
(-8250 5450);
DISPLAY 0.872340 (-8250 5450);
DISPLAY INVISIBLE (-8250 5450);
FORCEPROP 1 LAST PATH I269
J 2
(-7923 5575);
DISPLAY 0.872340 (-7923 5575);
PAINT GREEN (-7923 5575);
DISPLAY INVISIBLE (-7923 5575);
FORCEADD TAP..1
R 2
(-7925 5675);
FORCEPROP 3 LASTPIN (-7875 5675) SIG_NAME M_C_CPU0_SA_CA<5>
J 0
(-7865 5685);
DISPLAY 0.659574 (-7865 5685);
PAINT MONO (-7865 5685);
DISPLAY INVISIBLE (-7865 5685);
FORCEPROP 1 LASTPIN (-7875 5675) BN 5
J 2
(-7863 5683);
DISPLAY 0.489362 (-7863 5683);
PAINT GREEN (-7863 5683);
FORCEPROP 2 LAST CDS_LIB mstr_standard
J 0
(-7925 5675);
DISPLAY 0.723404 (-7925 5675);
PAINT MONO (-7925 5675);
DISPLAY INVISIBLE (-7925 5675);
FORCEPROP 1 LAST BODY_TYPE PLUMBING
J 2
(-7925 5725);
DISPLAY 0.872340 (-7925 5725);
PAINT GREEN (-7925 5725);
DISPLAY INVISIBLE (-7925 5725);
FORCEPROP 1 LAST HDL_TAP TRUE
J 2
(-8250 5550);
DISPLAY 0.872340 (-8250 5550);
DISPLAY INVISIBLE (-8250 5550);
FORCEPROP 1 LAST PATH I270
J 2
(-7923 5675);
DISPLAY 0.872340 (-7923 5675);
PAINT GREEN (-7923 5675);
DISPLAY INVISIBLE (-7923 5675);
FORCEADD TAP..1
R 2
(-7925 5625);
FORCEPROP 3 LASTPIN (-7875 5625) SIG_NAME M_C_CPU0_SA_CA<4>
J 0
(-7865 5635);
DISPLAY 0.659574 (-7865 5635);
PAINT MONO (-7865 5635);
DISPLAY INVISIBLE (-7865 5635);
FORCEPROP 1 LASTPIN (-7875 5625) BN 4
J 2
(-7863 5633);
DISPLAY 0.489362 (-7863 5633);
PAINT GREEN (-7863 5633);
FORCEPROP 2 LAST CDS_LIB mstr_standard
J 0
(-7925 5625);
DISPLAY 0.723404 (-7925 5625);
PAINT MONO (-7925 5625);
DISPLAY INVISIBLE (-7925 5625);
FORCEPROP 1 LAST BODY_TYPE PLUMBING
J 2
(-7925 5675);
DISPLAY 0.872340 (-7925 5675);
PAINT GREEN (-7925 5675);
DISPLAY INVISIBLE (-7925 5675);
FORCEPROP 1 LAST HDL_TAP TRUE
J 2
(-8250 5500);
DISPLAY 0.872340 (-8250 5500);
DISPLAY INVISIBLE (-8250 5500);
FORCEPROP 1 LAST PATH I271
J 2
(-7923 5625);
DISPLAY 0.872340 (-7923 5625);
PAINT GREEN (-7923 5625);
DISPLAY INVISIBLE (-7923 5625);
FORCEADD TAP..1
R 2
(-7925 5725);
FORCEPROP 3 LASTPIN (-7875 5725) SIG_NAME M_C_CPU0_SA_CA<6>
J 0
(-7865 5735);
DISPLAY 0.659574 (-7865 5735);
PAINT MONO (-7865 5735);
DISPLAY INVISIBLE (-7865 5735);
FORCEPROP 1 LASTPIN (-7875 5725) BN 6
J 2
(-7863 5733);
DISPLAY 0.489362 (-7863 5733);
PAINT GREEN (-7863 5733);
FORCEPROP 2 LAST CDS_LIB mstr_standard
J 0
(-7925 5725);
DISPLAY 0.723404 (-7925 5725);
PAINT MONO (-7925 5725);
DISPLAY INVISIBLE (-7925 5725);
FORCEPROP 1 LAST BODY_TYPE PLUMBING
J 2
(-7925 5775);
DISPLAY 0.872340 (-7925 5775);
PAINT GREEN (-7925 5775);
DISPLAY INVISIBLE (-7925 5775);
FORCEPROP 1 LAST HDL_TAP TRUE
J 2
(-8250 5600);
DISPLAY 0.872340 (-8250 5600);
DISPLAY INVISIBLE (-8250 5600);
FORCEPROP 1 LAST PATH I272
J 2
(-7923 5725);
DISPLAY 0.872340 (-7923 5725);
PAINT GREEN (-7923 5725);
DISPLAY INVISIBLE (-7923 5725);
FORCEADD TAP..1
(-6225 5325);
FORCEPROP 3 LASTPIN (-6275 5325) SIG_NAME M_C_CPU0_SA_DQ<23>
J 0
(-6265 5335);
DISPLAY 0.659574 (-6265 5335);
PAINT MONO (-6265 5335);
DISPLAY INVISIBLE (-6265 5335);
FORCEPROP 1 LASTPIN (-6275 5325) BN 23
J 0
(-6287 5333);
DISPLAY 0.489362 (-6287 5333);
PAINT GREEN (-6287 5333);
FORCEPROP 2 LAST CDS_LIB mstr_standard
J 0
(-6225 5325);
DISPLAY 0.723404 (-6225 5325);
PAINT MONO (-6225 5325);
DISPLAY INVISIBLE (-6225 5325);
FORCEPROP 1 LAST BODY_TYPE PLUMBING
J 0
(-6225 5375);
DISPLAY 0.872340 (-6225 5375);
PAINT GREEN (-6225 5375);
DISPLAY INVISIBLE (-6225 5375);
FORCEPROP 1 LAST HDL_TAP TRUE
J 0
(-5900 5200);
DISPLAY 0.872340 (-5900 5200);
DISPLAY INVISIBLE (-5900 5200);
FORCEPROP 1 LAST PATH I273
J 0
(-6227 5325);
DISPLAY 0.872340 (-6227 5325);
PAINT GREEN (-6227 5325);
DISPLAY INVISIBLE (-6227 5325);
FORCEADD TAP..1
(-6225 5225);
FORCEPROP 3 LASTPIN (-6275 5225) SIG_NAME M_C_CPU0_SA_DQ<21>
J 0
(-6265 5235);
DISPLAY 0.659574 (-6265 5235);
PAINT MONO (-6265 5235);
DISPLAY INVISIBLE (-6265 5235);
FORCEPROP 1 LASTPIN (-6275 5225) BN 21
J 0
(-6287 5233);
DISPLAY 0.489362 (-6287 5233);
PAINT GREEN (-6287 5233);
FORCEPROP 2 LAST CDS_LIB mstr_standard
J 0
(-6225 5225);
DISPLAY 0.723404 (-6225 5225);
PAINT MONO (-6225 5225);
DISPLAY INVISIBLE (-6225 5225);
FORCEPROP 1 LAST BODY_TYPE PLUMBING
J 0
(-6225 5275);
DISPLAY 0.872340 (-6225 5275);
PAINT GREEN (-6225 5275);
DISPLAY INVISIBLE (-6225 5275);
FORCEPROP 1 LAST HDL_TAP TRUE
J 0
(-5900 5100);
DISPLAY 0.872340 (-5900 5100);
DISPLAY INVISIBLE (-5900 5100);
FORCEPROP 1 LAST PATH I274
J 0
(-6227 5225);
DISPLAY 0.872340 (-6227 5225);
PAINT GREEN (-6227 5225);
DISPLAY INVISIBLE (-6227 5225);
FORCEADD TAP..1
(-6225 5275);
FORCEPROP 3 LASTPIN (-6275 5275) SIG_NAME M_C_CPU0_SA_DQ<22>
J 0
(-6265 5285);
DISPLAY 0.659574 (-6265 5285);
PAINT MONO (-6265 5285);
DISPLAY INVISIBLE (-6265 5285);
FORCEPROP 1 LASTPIN (-6275 5275) BN 22
J 0
(-6287 5283);
DISPLAY 0.489362 (-6287 5283);
PAINT GREEN (-6287 5283);
FORCEPROP 2 LAST CDS_LIB mstr_standard
J 0
(-6225 5275);
DISPLAY 0.723404 (-6225 5275);
PAINT MONO (-6225 5275);
DISPLAY INVISIBLE (-6225 5275);
FORCEPROP 1 LAST BODY_TYPE PLUMBING
J 0
(-6225 5325);
DISPLAY 0.872340 (-6225 5325);
PAINT GREEN (-6225 5325);
DISPLAY INVISIBLE (-6225 5325);
FORCEPROP 1 LAST HDL_TAP TRUE
J 0
(-5900 5150);
DISPLAY 0.872340 (-5900 5150);
DISPLAY INVISIBLE (-5900 5150);
FORCEPROP 1 LAST PATH I275
J 0
(-6227 5275);
DISPLAY 0.872340 (-6227 5275);
PAINT GREEN (-6227 5275);
DISPLAY INVISIBLE (-6227 5275);
FORCEADD TAP..1
(-6225 5375);
FORCEPROP 3 LASTPIN (-6275 5375) SIG_NAME M_C_CPU0_SA_DQ<24>
J 0
(-6265 5385);
DISPLAY 0.659574 (-6265 5385);
PAINT MONO (-6265 5385);
DISPLAY INVISIBLE (-6265 5385);
FORCEPROP 1 LASTPIN (-6275 5375) BN 24
J 0
(-6287 5383);
DISPLAY 0.489362 (-6287 5383);
PAINT GREEN (-6287 5383);
FORCEPROP 2 LAST CDS_LIB mstr_standard
J 0
(-6225 5375);
DISPLAY 0.723404 (-6225 5375);
PAINT MONO (-6225 5375);
DISPLAY INVISIBLE (-6225 5375);
FORCEPROP 1 LAST BODY_TYPE PLUMBING
J 0
(-6225 5425);
DISPLAY 0.872340 (-6225 5425);
PAINT GREEN (-6225 5425);
DISPLAY INVISIBLE (-6225 5425);
FORCEPROP 1 LAST HDL_TAP TRUE
J 0
(-5900 5250);
DISPLAY 0.872340 (-5900 5250);
DISPLAY INVISIBLE (-5900 5250);
FORCEPROP 1 LAST PATH I276
J 0
(-6227 5375);
DISPLAY 0.872340 (-6227 5375);
PAINT GREEN (-6227 5375);
DISPLAY INVISIBLE (-6227 5375);
FORCEADD TAP..1
(-6225 5425);
FORCEPROP 3 LASTPIN (-6275 5425) SIG_NAME M_C_CPU0_SA_DQ<25>
J 0
(-6265 5435);
DISPLAY 0.659574 (-6265 5435);
PAINT MONO (-6265 5435);
DISPLAY INVISIBLE (-6265 5435);
FORCEPROP 1 LASTPIN (-6275 5425) BN 25
J 0
(-6287 5433);
DISPLAY 0.489362 (-6287 5433);
PAINT GREEN (-6287 5433);
FORCEPROP 2 LAST CDS_LIB mstr_standard
J 0
(-6225 5425);
DISPLAY 0.723404 (-6225 5425);
PAINT MONO (-6225 5425);
DISPLAY INVISIBLE (-6225 5425);
FORCEPROP 1 LAST BODY_TYPE PLUMBING
J 0
(-6225 5475);
DISPLAY 0.872340 (-6225 5475);
PAINT GREEN (-6225 5475);
DISPLAY INVISIBLE (-6225 5475);
FORCEPROP 1 LAST HDL_TAP TRUE
J 0
(-5900 5300);
DISPLAY 0.872340 (-5900 5300);
DISPLAY INVISIBLE (-5900 5300);
FORCEPROP 1 LAST PATH I277
J 0
(-6227 5425);
DISPLAY 0.872340 (-6227 5425);
PAINT GREEN (-6227 5425);
DISPLAY INVISIBLE (-6227 5425);
FORCEADD TAP..1
(-6225 5475);
FORCEPROP 3 LASTPIN (-6275 5475) SIG_NAME M_C_CPU0_SA_DQ<26>
J 0
(-6265 5485);
DISPLAY 0.659574 (-6265 5485);
PAINT MONO (-6265 5485);
DISPLAY INVISIBLE (-6265 5485);
FORCEPROP 1 LASTPIN (-6275 5475) BN 26
J 0
(-6287 5483);
DISPLAY 0.489362 (-6287 5483);
PAINT GREEN (-6287 5483);
FORCEPROP 2 LAST CDS_LIB mstr_standard
J 0
(-6225 5475);
DISPLAY 0.723404 (-6225 5475);
PAINT MONO (-6225 5475);
DISPLAY INVISIBLE (-6225 5475);
FORCEPROP 1 LAST BODY_TYPE PLUMBING
J 0
(-6225 5525);
DISPLAY 0.872340 (-6225 5525);
PAINT GREEN (-6225 5525);
DISPLAY INVISIBLE (-6225 5525);
FORCEPROP 1 LAST HDL_TAP TRUE
J 0
(-5900 5350);
DISPLAY 0.872340 (-5900 5350);
DISPLAY INVISIBLE (-5900 5350);
FORCEPROP 1 LAST PATH I278
J 0
(-6227 5475);
DISPLAY 0.872340 (-6227 5475);
PAINT GREEN (-6227 5475);
DISPLAY INVISIBLE (-6227 5475);
FORCEADD TAP..1
(-6225 5725);
FORCEPROP 3 LASTPIN (-6275 5725) SIG_NAME M_C_CPU0_SA_DQ<31>
J 0
(-6265 5735);
DISPLAY 0.659574 (-6265 5735);
PAINT MONO (-6265 5735);
DISPLAY INVISIBLE (-6265 5735);
FORCEPROP 1 LASTPIN (-6275 5725) BN 31
J 0
(-6287 5733);
DISPLAY 0.489362 (-6287 5733);
PAINT GREEN (-6287 5733);
FORCEPROP 2 LAST CDS_LIB mstr_standard
J 0
(-6225 5725);
DISPLAY 0.723404 (-6225 5725);
PAINT MONO (-6225 5725);
DISPLAY INVISIBLE (-6225 5725);
FORCEPROP 1 LAST BODY_TYPE PLUMBING
J 0
(-6225 5775);
DISPLAY 0.872340 (-6225 5775);
PAINT GREEN (-6225 5775);
DISPLAY INVISIBLE (-6225 5775);
FORCEPROP 1 LAST HDL_TAP TRUE
J 0
(-5900 5600);
DISPLAY 0.872340 (-5900 5600);
DISPLAY INVISIBLE (-5900 5600);
FORCEPROP 1 LAST PATH I279
J 0
(-6227 5725);
DISPLAY 0.872340 (-6227 5725);
PAINT GREEN (-6227 5725);
DISPLAY INVISIBLE (-6227 5725);
FORCEADD TAP..1
(-6225 5525);
FORCEPROP 3 LASTPIN (-6275 5525) SIG_NAME M_C_CPU0_SA_DQ<27>
J 0
(-6265 5535);
DISPLAY 0.659574 (-6265 5535);
PAINT MONO (-6265 5535);
DISPLAY INVISIBLE (-6265 5535);
FORCEPROP 1 LASTPIN (-6275 5525) BN 27
J 0
(-6287 5533);
DISPLAY 0.489362 (-6287 5533);
PAINT GREEN (-6287 5533);
FORCEPROP 2 LAST CDS_LIB mstr_standard
J 0
(-6225 5525);
DISPLAY 0.723404 (-6225 5525);
PAINT MONO (-6225 5525);
DISPLAY INVISIBLE (-6225 5525);
FORCEPROP 1 LAST BODY_TYPE PLUMBING
J 0
(-6225 5575);
DISPLAY 0.872340 (-6225 5575);
PAINT GREEN (-6225 5575);
DISPLAY INVISIBLE (-6225 5575);
FORCEPROP 1 LAST HDL_TAP TRUE
J 0
(-5900 5400);
DISPLAY 0.872340 (-5900 5400);
DISPLAY INVISIBLE (-5900 5400);
FORCEPROP 1 LAST PATH I280
J 0
(-6227 5525);
DISPLAY 0.872340 (-6227 5525);
PAINT GREEN (-6227 5525);
DISPLAY INVISIBLE (-6227 5525);
FORCEADD TAP..1
(-6225 5575);
FORCEPROP 3 LASTPIN (-6275 5575) SIG_NAME M_C_CPU0_SA_DQ<28>
J 0
(-6265 5585);
DISPLAY 0.659574 (-6265 5585);
PAINT MONO (-6265 5585);
DISPLAY INVISIBLE (-6265 5585);
FORCEPROP 1 LASTPIN (-6275 5575) BN 28
J 0
(-6287 5583);
DISPLAY 0.489362 (-6287 5583);
PAINT GREEN (-6287 5583);
FORCEPROP 2 LAST CDS_LIB mstr_standard
J 0
(-6225 5575);
DISPLAY 0.723404 (-6225 5575);
PAINT MONO (-6225 5575);
DISPLAY INVISIBLE (-6225 5575);
FORCEPROP 1 LAST BODY_TYPE PLUMBING
J 0
(-6225 5625);
DISPLAY 0.872340 (-6225 5625);
PAINT GREEN (-6225 5625);
DISPLAY INVISIBLE (-6225 5625);
FORCEPROP 1 LAST HDL_TAP TRUE
J 0
(-5900 5450);
DISPLAY 0.872340 (-5900 5450);
DISPLAY INVISIBLE (-5900 5450);
FORCEPROP 1 LAST PATH I281
J 0
(-6227 5575);
DISPLAY 0.872340 (-6227 5575);
PAINT GREEN (-6227 5575);
DISPLAY INVISIBLE (-6227 5575);
FORCEADD TAP..1
(-6225 5675);
FORCEPROP 3 LASTPIN (-6275 5675) SIG_NAME M_C_CPU0_SA_DQ<30>
J 0
(-6265 5685);
DISPLAY 0.659574 (-6265 5685);
PAINT MONO (-6265 5685);
DISPLAY INVISIBLE (-6265 5685);
FORCEPROP 1 LASTPIN (-6275 5675) BN 30
J 0
(-6287 5683);
DISPLAY 0.489362 (-6287 5683);
PAINT GREEN (-6287 5683);
FORCEPROP 2 LAST CDS_LIB mstr_standard
J 0
(-6225 5675);
DISPLAY 0.723404 (-6225 5675);
PAINT MONO (-6225 5675);
DISPLAY INVISIBLE (-6225 5675);
FORCEPROP 1 LAST BODY_TYPE PLUMBING
J 0
(-6225 5725);
DISPLAY 0.872340 (-6225 5725);
PAINT GREEN (-6225 5725);
DISPLAY INVISIBLE (-6225 5725);
FORCEPROP 1 LAST HDL_TAP TRUE
J 0
(-5900 5550);
DISPLAY 0.872340 (-5900 5550);
DISPLAY INVISIBLE (-5900 5550);
FORCEPROP 1 LAST PATH I282
J 0
(-6227 5675);
DISPLAY 0.872340 (-6227 5675);
PAINT GREEN (-6227 5675);
DISPLAY INVISIBLE (-6227 5675);
FORCEADD TAP..1
(-6225 5625);
FORCEPROP 3 LASTPIN (-6275 5625) SIG_NAME M_C_CPU0_SA_DQ<29>
J 0
(-6265 5635);
DISPLAY 0.659574 (-6265 5635);
PAINT MONO (-6265 5635);
DISPLAY INVISIBLE (-6265 5635);
FORCEPROP 1 LASTPIN (-6275 5625) BN 29
J 0
(-6287 5633);
DISPLAY 0.489362 (-6287 5633);
PAINT GREEN (-6287 5633);
FORCEPROP 2 LAST CDS_LIB mstr_standard
J 0
(-6225 5625);
DISPLAY 0.723404 (-6225 5625);
PAINT MONO (-6225 5625);
DISPLAY INVISIBLE (-6225 5625);
FORCEPROP 1 LAST BODY_TYPE PLUMBING
J 0
(-6225 5675);
DISPLAY 0.872340 (-6225 5675);
PAINT GREEN (-6225 5675);
DISPLAY INVISIBLE (-6225 5675);
FORCEPROP 1 LAST HDL_TAP TRUE
J 0
(-5900 5500);
DISPLAY 0.872340 (-5900 5500);
DISPLAY INVISIBLE (-5900 5500);
FORCEPROP 1 LAST PATH I283
J 0
(-6227 5625);
DISPLAY 0.872340 (-6227 5625);
PAINT GREEN (-6227 5625);
DISPLAY INVISIBLE (-6227 5625);
FORCEADD OFFPAGE..3
(-5675 5775);
FORCEPROP 2 LAST $XR0 12 
J 0
(-5461 5775);
DISPLAY 0.638298 (-5461 5775);
PAINT MONO (-5461 5775);
FORCEPROP 2 LAST CDS_LIB mstr_standard
J 0
(-5675 5775);
DISPLAY 0.723404 (-5675 5775);
PAINT MONO (-5675 5775);
DISPLAY INVISIBLE (-5675 5775);
FORCEPROP 1 LAST OFFPAGE TRUE
J 0
(-5350 5650);
DISPLAY 0.872340 (-5350 5650);
PAINT GREEN (-5350 5650);
DISPLAY INVISIBLE (-5350 5650);
FORCEPROP 1 LAST COMMENT_BODY TRUE
J 0
(-5725 5675);
DISPLAY 0.872340 (-5725 5675);
PAINT GREEN (-5725 5675);
DISPLAY INVISIBLE (-5725 5675);
FORCEPROP 2 LAST PATH I284
J 0
(-5450 5825);
DISPLAY 0.808511 (-5450 5825);
DISPLAY INVISIBLE (-5450 5825);
FORCEADD GND..1
(-6625 1350);
FORCEPROP 3 LASTPIN (-6625 1400) SIG_NAME GND\g
J 0
(-6615 1410);
DISPLAY 0.659574 (-6615 1410);
PAINT MONO (-6615 1410);
DISPLAY INVISIBLE (-6615 1410);
FORCEPROP 2 LAST BOM_COST MEM
J 0
(-6725 1425);
DISPLAY 0.808511 (-6725 1425);
DISPLAY INVISIBLE (-6725 1425);
FORCEPROP 2 LAST CDS_LIB mstr_symbols
J 0
(-6625 1350);
DISPLAY 0.808511 (-6625 1350);
DISPLAY INVISIBLE (-6625 1350);
FORCEPROP 1 LAST SIZE 1B
J 0
(-6550 1300);
DISPLAY 0.851064 (-6550 1300);
PAINT GREEN (-6550 1300);
DISPLAY INVISIBLE (-6550 1300);
FORCEPROP 1 LAST VOLTAGE 0.0
J 0
(-6670 1307);
DISPLAY 0.723404 (-6670 1307);
PAINT SKYBLUE (-6670 1307);
DISPLAY INVISIBLE (-6670 1307);
FORCEPROP 1 LAST BODY_TYPE PLUMBING
J 0
(-6670 1307);
DISPLAY 0.340426 (-6670 1307);
PAINT GREEN (-6670 1307);
DISPLAY INVISIBLE (-6670 1307);
FORCEPROP 1 LAST HDL_POWER GND
J 0
(-6625 1500);
DISPLAY 0.851064 (-6625 1500);
PAINT GREEN (-6625 1500);
DISPLAY INVISIBLE (-6625 1500);
FORCEPROP 1 LAST PATH I332
J 0
(-6550 1350);
DISPLAY 0.872340 (-6550 1350);
PAINT GREEN (-6550 1350);
DISPLAY INVISIBLE (-6550 1350);
FORCEADD OFFPAGE..5
(-7400 1750);
FORCEPROP 2 LAST $XR0 88 
J 0
(-7654 1750);
DISPLAY 0.638298 (-7654 1750);
PAINT MONO (-7654 1750);
FORCEPROP 2 LAST BOM_COST MEM
J 0
(-7475 1825);
DISPLAY 0.808511 (-7475 1825);
DISPLAY INVISIBLE (-7475 1825);
FORCEPROP 2 LAST CDS_LIB mstr_standard
J 0
(-7400 1750);
DISPLAY 0.808511 (-7400 1750);
DISPLAY INVISIBLE (-7400 1750);
FORCEPROP 1 LAST OFFPAGE TRUE
J 0
(-7075 1625);
DISPLAY 0.872340 (-7075 1625);
PAINT GREEN (-7075 1625);
DISPLAY INVISIBLE (-7075 1625);
FORCEPROP 1 LAST COMMENT_BODY TRUE
J 0
(-7300 1675);
DISPLAY 0.872340 (-7300 1675);
PAINT GREEN (-7300 1675);
DISPLAY INVISIBLE (-7300 1675);
FORCEPROP 2 LAST PATH I333
J 0
(-7350 1825);
DISPLAY 0.808511 (-7350 1825);
DISPLAY INVISIBLE (-7350 1825);
FORCEADD OFFPAGE..1
(-8525 3225);
FORCEPROP 2 LAST $XR0 88 
J 0
(-8746 3225);
DISPLAY 0.638298 (-8746 3225);
PAINT MONO (-8746 3225);
FORCEPROP 2 LAST CDS_LIB mstr_standard
J 0
(-8525 3225);
DISPLAY 0.808511 (-8525 3225);
DISPLAY INVISIBLE (-8525 3225);
FORCEPROP 1 LAST OFFPAGE TRUE
J 0
(-8200 3100);
DISPLAY 0.872340 (-8200 3100);
PAINT GREEN (-8200 3100);
DISPLAY INVISIBLE (-8200 3100);
FORCEPROP 1 LAST COMMENT_BODY TRUE
J 0
(-8400 3125);
DISPLAY 0.872340 (-8400 3125);
PAINT GREEN (-8400 3125);
DISPLAY INVISIBLE (-8400 3125);
FORCEPROP 2 LAST PATH I334
J 0
(-8475 3300);
DISPLAY 0.808511 (-8475 3300);
DISPLAY INVISIBLE (-8475 3300);
FORCEADD Q_RES..2
(-6625 1575);
FORCEPROP 1 LAST LOCATION R762
J 0
(-6580 1700);
DISPLAY 0.489362 (-6580 1700);
PAINT SKYBLUE (-6580 1700);
FORCEPROP 0 LAST $SEC 1
J 0
(-6575 1750);
DISPLAY 0.680851 (-6575 1750);
PAINT MONO (-6575 1750);
DISPLAY INVISIBLE (-6575 1750);
FORCEPROP 0 LAST CDS_SEC 1
J 0
(-6575 1750);
DISPLAY 1.021277 (-6575 1750);
DISPLAY INVISIBLE (-6575 1750);
FORCEPROP 1 LASTPIN (-6625 1675) $PN 1
J 0
(-6620 1637);
DISPLAY 0.489362 (-6620 1637);
PAINT MONO (-6620 1637);
FORCEPROP 1 LASTPIN (-6625 1475) $PN 2
J 0
(-6620 1485);
DISPLAY 0.489362 (-6620 1485);
PAINT MONO (-6620 1485);
FORCEPROP 1 LAST WATTAGE 1/16W
J 0
(-6585 1550);
DISPLAY 0.489362 (-6585 1550);
PAINT SKYBLUE (-6585 1550);
FORCEPROP 1 LAST MATERIAL CHIP
J 0
(-6585 1500);
DISPLAY 0.489362 (-6585 1500);
PAINT SKYBLUE (-6585 1500);
FORCEPROP 1 LAST TOLERANCE 1%
J 0
(-6580 1600);
DISPLAY 0.489362 (-6580 1600);
PAINT SKYBLUE (-6580 1600);
FORCEPROP 1 LAST VALUE 23.2K
J 0
(-6580 1650);
DISPLAY 0.489362 (-6580 1650);
PAINT SKYBLUE (-6580 1650);
FORCEPROP 1 LAST PACK_TYPE 0402LF
J 0
(-6585 1400);
DISPLAY 0.489362 (-6585 1400);
PAINT SKYBLUE (-6585 1400);
FORCEPROP 2 LAST CDS_LIB pure_quanta
J 0
(-6625 1575);
DISPLAY INVISIBLE (-6625 1575);
FORCEPROP 1 LAST PATH I349
J 0
(-6575 1750);
DISPLAY 0.978723 (-6575 1750);
PAINT WHITE (-6575 1750);
DISPLAY INVISIBLE (-6575 1750);
FORCEPROP 1 LAST PART_NUMBER CS32322FB03
J 0
(-6585 1450);
DISPLAY 0.489362 (-6585 1450);
PAINT SKYBLUE (-6585 1450);
DISPLAY INVISIBLE (-6585 1450);
FORCEADD SCONN288_DDR506112002KQ..1
(-7075 3975);
FORCEPROP 1 LAST LOCATION J17
J 0
(-7525 6050);
DISPLAY 0.468085 (-7525 6050);
PAINT SKYBLUE (-7525 6050);
FORCEPROP 0 LAST $SEC 1
J 0
(-7525 6200);
DISPLAY 0.680851 (-7525 6200);
PAINT MONO (-7525 6200);
DISPLAY INVISIBLE (-7525 6200);
FORCEPROP 2 LAST CDS_SEC 1
J 0
(-7525 6200);
DISPLAY 1.021277 (-7525 6200);
DISPLAY INVISIBLE (-7525 6200);
FORCEPROP 0 LASTPIN (-7675 3375) $PN 62
J 2
(-7685 3385);
DISPLAY 0.680851 (-7685 3385);
PAINT MONO (-7685 3385);
FORCEPROP 0 LASTPIN (-7675 5425) $PN 66
J 2
(-7685 5435);
DISPLAY 0.680851 (-7685 5435);
PAINT MONO (-7685 5435);
FORCEPROP 0 LASTPIN (-7675 5025) $PN 76
J 2
(-7685 5035);
DISPLAY 0.680851 (-7685 5035);
PAINT MONO (-7685 5035);
FORCEPROP 0 LASTPIN (-7675 5475) $PN 211
J 2
(-7685 5485);
DISPLAY 0.680851 (-7685 5485);
PAINT MONO (-7685 5485);
FORCEPROP 0 LASTPIN (-7675 5075) $PN 221
J 2
(-7685 5085);
DISPLAY 0.680851 (-7685 5085);
PAINT MONO (-7685 5085);
FORCEPROP 0 LASTPIN (-7675 5525) $PN 68
J 2
(-7685 5535);
DISPLAY 0.680851 (-7685 5535);
PAINT MONO (-7685 5535);
FORCEPROP 0 LASTPIN (-7675 5125) $PN 78
J 2
(-7685 5135);
DISPLAY 0.680851 (-7685 5135);
PAINT MONO (-7685 5135);
FORCEPROP 0 LASTPIN (-7675 5575) $PN 213
J 2
(-7685 5585);
DISPLAY 0.680851 (-7685 5585);
PAINT MONO (-7685 5585);
FORCEPROP 0 LASTPIN (-7675 5175) $PN 223
J 2
(-7685 5185);
DISPLAY 0.680851 (-7685 5185);
PAINT MONO (-7685 5185);
FORCEPROP 0 LASTPIN (-7675 5625) $PN 70
J 2
(-7685 5635);
DISPLAY 0.680851 (-7685 5635);
PAINT MONO (-7685 5635);
FORCEPROP 0 LASTPIN (-7675 5225) $PN 80
J 2
(-7685 5235);
DISPLAY 0.680851 (-7685 5235);
PAINT MONO (-7685 5235);
FORCEPROP 0 LASTPIN (-7675 5675) $PN 215
J 2
(-7685 5685);
DISPLAY 0.680851 (-7685 5685);
PAINT MONO (-7685 5685);
FORCEPROP 0 LASTPIN (-7675 5275) $PN 225
J 2
(-7685 5285);
DISPLAY 0.680851 (-7685 5285);
PAINT MONO (-7685 5285);
FORCEPROP 0 LASTPIN (-7675 5725) $PN 72
J 2
(-7685 5735);
DISPLAY 0.680851 (-7685 5735);
PAINT MONO (-7685 5735);
FORCEPROP 0 LASTPIN (-7675 5325) $PN 82
J 2
(-7685 5335);
DISPLAY 0.680851 (-7685 5335);
PAINT MONO (-7685 5335);
FORCEPROP 0 LASTPIN (-7675 3975) $PN 51
J 2
(-7685 3985);
DISPLAY 0.680851 (-7685 3985);
PAINT MONO (-7685 3985);
FORCEPROP 0 LASTPIN (-7675 3525) $PN 96
J 2
(-7685 3535);
DISPLAY 0.680851 (-7685 3535);
PAINT MONO (-7685 3535);
FORCEPROP 0 LASTPIN (-7675 4025) $PN 53
J 2
(-7685 4035);
DISPLAY 0.680851 (-7685 4035);
PAINT MONO (-7685 4035);
FORCEPROP 0 LASTPIN (-7675 3575) $PN 98
J 2
(-7685 3585);
DISPLAY 0.680851 (-7685 3585);
PAINT MONO (-7685 3585);
FORCEPROP 0 LASTPIN (-7675 4075) $PN 196
J 2
(-7685 4085);
DISPLAY 0.680851 (-7685 4085);
PAINT MONO (-7685 4085);
FORCEPROP 0 LASTPIN (-7675 3625) $PN 241
J 2
(-7685 3635);
DISPLAY 0.680851 (-7685 3635);
PAINT MONO (-7685 3635);
FORCEPROP 0 LASTPIN (-7675 4125) $PN 198
J 2
(-7685 4135);
DISPLAY 0.680851 (-7685 4135);
PAINT MONO (-7685 4135);
FORCEPROP 0 LASTPIN (-7675 3675) $PN 243
J 2
(-7685 3685);
DISPLAY 0.680851 (-7685 3685);
PAINT MONO (-7685 3685);
FORCEPROP 0 LASTPIN (-7675 4175) $PN 58
J 2
(-7685 4185);
DISPLAY 0.680851 (-7685 4185);
PAINT MONO (-7685 4185);
FORCEPROP 0 LASTPIN (-7675 3725) $PN 89
J 2
(-7685 3735);
DISPLAY 0.680851 (-7685 3735);
PAINT MONO (-7685 3735);
FORCEPROP 0 LASTPIN (-7675 4225) $PN 60
J 2
(-7685 4235);
DISPLAY 0.680851 (-7685 4235);
PAINT MONO (-7685 4235);
FORCEPROP 0 LASTPIN (-7675 3775) $PN 91
J 2
(-7685 3785);
DISPLAY 0.680851 (-7685 3785);
PAINT MONO (-7685 3785);
FORCEPROP 0 LASTPIN (-7675 4275) $PN 203
J 2
(-7685 4285);
DISPLAY 0.680851 (-7685 4285);
PAINT MONO (-7685 4285);
FORCEPROP 0 LASTPIN (-7675 3825) $PN 234
J 2
(-7685 3835);
DISPLAY 0.680851 (-7685 3835);
PAINT MONO (-7685 3835);
FORCEPROP 0 LASTPIN (-7675 4325) $PN 205
J 2
(-7685 4335);
DISPLAY 0.680851 (-7685 4335);
PAINT MONO (-7685 4335);
FORCEPROP 0 LASTPIN (-7675 3875) $PN 236
J 2
(-7685 3885);
DISPLAY 0.680851 (-7685 3885);
PAINT MONO (-7685 3885);
FORCEPROP 0 LASTPIN (-7675 4425) $PN 218
J 2
(-7685 4435);
DISPLAY 0.680851 (-7685 4435);
PAINT MONO (-7685 4435);
FORCEPROP 0 LASTPIN (-7675 4475) $PN 217
J 2
(-7685 4485);
DISPLAY 0.680851 (-7685 4485);
PAINT MONO (-7685 4485);
FORCEPROP 0 LASTPIN (-7675 4725) $PN 64
J 2
(-7685 4735);
DISPLAY 0.680851 (-7685 4735);
PAINT MONO (-7685 4735);
FORCEPROP 0 LASTPIN (-7675 4575) $PN 84
J 2
(-7685 4585);
DISPLAY 0.680851 (-7685 4585);
PAINT MONO (-7685 4585);
FORCEPROP 0 LASTPIN (-7675 4775) $PN 209
J 2
(-7685 4785);
DISPLAY 0.680851 (-7685 4785);
PAINT MONO (-7685 4785);
FORCEPROP 0 LASTPIN (-7675 4625) $PN 229
J 2
(-7685 4635);
DISPLAY 0.680851 (-7685 4635);
PAINT MONO (-7685 4635);
FORCEPROP 0 LASTPIN (-6475 4175) $PN 7
J 0
(-6465 4185);
DISPLAY 0.680851 (-6465 4185);
PAINT MONO (-6465 4185);
FORCEPROP 0 LASTPIN (-6475 2525) $PN 100
J 0
(-6465 2535);
DISPLAY 0.680851 (-6465 2535);
PAINT MONO (-6465 2535);
FORCEPROP 0 LASTPIN (-6475 4225) $PN 9
J 0
(-6465 4235);
DISPLAY 0.680851 (-6465 4235);
PAINT MONO (-6465 4235);
FORCEPROP 0 LASTPIN (-6475 2575) $PN 102
J 0
(-6465 2585);
DISPLAY 0.680851 (-6465 2585);
PAINT MONO (-6465 2585);
FORCEPROP 0 LASTPIN (-6475 4275) $PN 152
J 0
(-6465 4285);
DISPLAY 0.680851 (-6465 4285);
PAINT MONO (-6465 4285);
FORCEPROP 0 LASTPIN (-6475 2625) $PN 245
J 0
(-6465 2635);
DISPLAY 0.680851 (-6465 2635);
PAINT MONO (-6465 2635);
FORCEPROP 0 LASTPIN (-6475 4325) $PN 154
J 0
(-6465 4335);
DISPLAY 0.680851 (-6465 4335);
PAINT MONO (-6465 4335);
FORCEPROP 0 LASTPIN (-6475 2675) $PN 247
J 0
(-6465 2685);
DISPLAY 0.680851 (-6465 2685);
PAINT MONO (-6465 2685);
FORCEPROP 0 LASTPIN (-6475 4375) $PN 14
J 0
(-6465 4385);
DISPLAY 0.680851 (-6465 4385);
PAINT MONO (-6465 4385);
FORCEPROP 0 LASTPIN (-6475 2725) $PN 107
J 0
(-6465 2735);
DISPLAY 0.680851 (-6465 2735);
PAINT MONO (-6465 2735);
FORCEPROP 0 LASTPIN (-6475 4425) $PN 16
J 0
(-6465 4435);
DISPLAY 0.680851 (-6465 4435);
PAINT MONO (-6465 4435);
FORCEPROP 0 LASTPIN (-6475 2775) $PN 109
J 0
(-6465 2785);
DISPLAY 0.680851 (-6465 2785);
PAINT MONO (-6465 2785);
FORCEPROP 0 LASTPIN (-6475 4475) $PN 159
J 0
(-6465 4485);
DISPLAY 0.680851 (-6465 4485);
PAINT MONO (-6465 4485);
FORCEPROP 0 LASTPIN (-6475 2825) $PN 252
J 0
(-6465 2835);
DISPLAY 0.680851 (-6465 2835);
PAINT MONO (-6465 2835);
FORCEPROP 0 LASTPIN (-6475 4525) $PN 161
J 0
(-6465 4535);
DISPLAY 0.680851 (-6465 4535);
PAINT MONO (-6465 4535);
FORCEPROP 0 LASTPIN (-6475 2875) $PN 254
J 0
(-6465 2885);
DISPLAY 0.680851 (-6465 2885);
PAINT MONO (-6465 2885);
FORCEPROP 0 LASTPIN (-6475 4575) $PN 18
J 0
(-6465 4585);
DISPLAY 0.680851 (-6465 4585);
PAINT MONO (-6465 4585);
FORCEPROP 0 LASTPIN (-6475 2925) $PN 111
J 0
(-6465 2935);
DISPLAY 0.680851 (-6465 2935);
PAINT MONO (-6465 2935);
FORCEPROP 0 LASTPIN (-6475 4625) $PN 20
J 0
(-6465 4635);
DISPLAY 0.680851 (-6465 4635);
PAINT MONO (-6465 4635);
FORCEPROP 0 LASTPIN (-6475 2975) $PN 113
J 0
(-6465 2985);
DISPLAY 0.680851 (-6465 2985);
PAINT MONO (-6465 2985);
FORCEPROP 0 LASTPIN (-6475 4675) $PN 163
J 0
(-6465 4685);
DISPLAY 0.680851 (-6465 4685);
PAINT MONO (-6465 4685);
FORCEPROP 0 LASTPIN (-6475 3025) $PN 256
J 0
(-6465 3035);
DISPLAY 0.680851 (-6465 3035);
PAINT MONO (-6465 3035);
FORCEPROP 0 LASTPIN (-6475 4725) $PN 165
J 0
(-6465 4735);
DISPLAY 0.680851 (-6465 4735);
PAINT MONO (-6465 4735);
FORCEPROP 0 LASTPIN (-6475 3075) $PN 258
J 0
(-6465 3085);
DISPLAY 0.680851 (-6465 3085);
PAINT MONO (-6465 3085);
FORCEPROP 0 LASTPIN (-6475 4775) $PN 25
J 0
(-6465 4785);
DISPLAY 0.680851 (-6465 4785);
PAINT MONO (-6465 4785);
FORCEPROP 0 LASTPIN (-6475 3125) $PN 118
J 0
(-6465 3135);
DISPLAY 0.680851 (-6465 3135);
PAINT MONO (-6465 3135);
FORCEPROP 0 LASTPIN (-6475 4825) $PN 27
J 0
(-6465 4835);
DISPLAY 0.680851 (-6465 4835);
PAINT MONO (-6465 4835);
FORCEPROP 0 LASTPIN (-6475 3175) $PN 120
J 0
(-6465 3185);
DISPLAY 0.680851 (-6465 3185);
PAINT MONO (-6465 3185);
FORCEPROP 0 LASTPIN (-6475 4875) $PN 170
J 0
(-6465 4885);
DISPLAY 0.680851 (-6465 4885);
PAINT MONO (-6465 4885);
FORCEPROP 0 LASTPIN (-6475 3225) $PN 263
J 0
(-6465 3235);
DISPLAY 0.680851 (-6465 3235);
PAINT MONO (-6465 3235);
FORCEPROP 0 LASTPIN (-6475 4925) $PN 172
J 0
(-6465 4935);
DISPLAY 0.680851 (-6465 4935);
PAINT MONO (-6465 4935);
FORCEPROP 0 LASTPIN (-6475 3275) $PN 265
J 0
(-6465 3285);
DISPLAY 0.680851 (-6465 3285);
PAINT MONO (-6465 3285);
FORCEPROP 0 LASTPIN (-6475 4975) $PN 29
J 0
(-6465 4985);
DISPLAY 0.680851 (-6465 4985);
PAINT MONO (-6465 4985);
FORCEPROP 0 LASTPIN (-6475 3325) $PN 122
J 0
(-6465 3335);
DISPLAY 0.680851 (-6465 3335);
PAINT MONO (-6465 3335);
FORCEPROP 0 LASTPIN (-6475 5025) $PN 31
J 0
(-6465 5035);
DISPLAY 0.680851 (-6465 5035);
PAINT MONO (-6465 5035);
FORCEPROP 0 LASTPIN (-6475 3375) $PN 124
J 0
(-6465 3385);
DISPLAY 0.680851 (-6465 3385);
PAINT MONO (-6465 3385);
FORCEPROP 0 LASTPIN (-6475 5075) $PN 174
J 0
(-6465 5085);
DISPLAY 0.680851 (-6465 5085);
PAINT MONO (-6465 5085);
FORCEPROP 0 LASTPIN (-6475 3425) $PN 267
J 0
(-6465 3435);
DISPLAY 0.680851 (-6465 3435);
PAINT MONO (-6465 3435);
FORCEPROP 0 LASTPIN (-6475 5125) $PN 176
J 0
(-6465 5135);
DISPLAY 0.680851 (-6465 5135);
PAINT MONO (-6465 5135);
FORCEPROP 0 LASTPIN (-6475 3475) $PN 269
J 0
(-6465 3485);
DISPLAY 0.680851 (-6465 3485);
PAINT MONO (-6465 3485);
FORCEPROP 0 LASTPIN (-6475 5175) $PN 36
J 0
(-6465 5185);
DISPLAY 0.680851 (-6465 5185);
PAINT MONO (-6465 5185);
FORCEPROP 0 LASTPIN (-6475 3525) $PN 129
J 0
(-6465 3535);
DISPLAY 0.680851 (-6465 3535);
PAINT MONO (-6465 3535);
FORCEPROP 0 LASTPIN (-6475 5225) $PN 38
J 0
(-6465 5235);
DISPLAY 0.680851 (-6465 5235);
PAINT MONO (-6465 5235);
FORCEPROP 0 LASTPIN (-6475 3575) $PN 131
J 0
(-6465 3585);
DISPLAY 0.680851 (-6465 3585);
PAINT MONO (-6465 3585);
FORCEPROP 0 LASTPIN (-6475 5275) $PN 181
J 0
(-6465 5285);
DISPLAY 0.680851 (-6465 5285);
PAINT MONO (-6465 5285);
FORCEPROP 0 LASTPIN (-6475 3625) $PN 274
J 0
(-6465 3635);
DISPLAY 0.680851 (-6465 3635);
PAINT MONO (-6465 3635);
FORCEPROP 0 LASTPIN (-6475 5325) $PN 183
J 0
(-6465 5335);
DISPLAY 0.680851 (-6465 5335);
PAINT MONO (-6465 5335);
FORCEPROP 0 LASTPIN (-6475 3675) $PN 276
J 0
(-6465 3685);
DISPLAY 0.680851 (-6465 3685);
PAINT MONO (-6465 3685);
FORCEPROP 0 LASTPIN (-6475 5375) $PN 40
J 0
(-6465 5385);
DISPLAY 0.680851 (-6465 5385);
PAINT MONO (-6465 5385);
FORCEPROP 0 LASTPIN (-6475 3725) $PN 133
J 0
(-6465 3735);
DISPLAY 0.680851 (-6465 3735);
PAINT MONO (-6465 3735);
FORCEPROP 0 LASTPIN (-6475 5425) $PN 42
J 0
(-6465 5435);
DISPLAY 0.680851 (-6465 5435);
PAINT MONO (-6465 5435);
FORCEPROP 0 LASTPIN (-6475 3775) $PN 135
J 0
(-6465 3785);
DISPLAY 0.680851 (-6465 3785);
PAINT MONO (-6465 3785);
FORCEPROP 0 LASTPIN (-6475 5475) $PN 185
J 0
(-6465 5485);
DISPLAY 0.680851 (-6465 5485);
PAINT MONO (-6465 5485);
FORCEPROP 0 LASTPIN (-6475 3825) $PN 278
J 0
(-6465 3835);
DISPLAY 0.680851 (-6465 3835);
PAINT MONO (-6465 3835);
FORCEPROP 0 LASTPIN (-6475 5525) $PN 187
J 0
(-6465 5535);
DISPLAY 0.680851 (-6465 5535);
PAINT MONO (-6465 5535);
FORCEPROP 0 LASTPIN (-6475 3875) $PN 280
J 0
(-6465 3885);
DISPLAY 0.680851 (-6465 3885);
PAINT MONO (-6465 3885);
FORCEPROP 0 LASTPIN (-6475 5575) $PN 47
J 0
(-6465 5585);
DISPLAY 0.680851 (-6465 5585);
PAINT MONO (-6465 5585);
FORCEPROP 0 LASTPIN (-6475 3925) $PN 140
J 0
(-6465 3935);
DISPLAY 0.680851 (-6465 3935);
PAINT MONO (-6465 3935);
FORCEPROP 0 LASTPIN (-6475 5625) $PN 49
J 0
(-6465 5635);
DISPLAY 0.680851 (-6465 5635);
PAINT MONO (-6465 5635);
FORCEPROP 0 LASTPIN (-6475 3975) $PN 142
J 0
(-6465 3985);
DISPLAY 0.680851 (-6465 3985);
PAINT MONO (-6465 3985);
FORCEPROP 0 LASTPIN (-6475 5675) $PN 192
J 0
(-6465 5685);
DISPLAY 0.680851 (-6465 5685);
PAINT MONO (-6465 5685);
FORCEPROP 0 LASTPIN (-6475 4025) $PN 285
J 0
(-6465 4035);
DISPLAY 0.680851 (-6465 4035);
PAINT MONO (-6465 4035);
FORCEPROP 0 LASTPIN (-6475 5725) $PN 194
J 0
(-6465 5735);
DISPLAY 0.680851 (-6465 5735);
PAINT MONO (-6465 5735);
FORCEPROP 0 LASTPIN (-6475 4075) $PN 287
J 0
(-6465 4085);
DISPLAY 0.680851 (-6465 4085);
PAINT MONO (-6465 4085);
FORCEPROP 0 LASTPIN (-7675 3225) $PN 148
J 2
(-7685 3235);
DISPLAY 0.680851 (-7685 3235);
PAINT MONO (-7685 3235);
FORCEPROP 0 LASTPIN (-7675 3125) $PN 4
J 2
(-7685 3135);
DISPLAY 0.680851 (-7685 3135);
PAINT MONO (-7685 3135);
FORCEPROP 0 LASTPIN (-7675 3175) $PN 5
J 2
(-7685 3185);
DISPLAY 0.680851 (-7685 3185);
PAINT MONO (-7685 3185);
FORCEPROP 0 LASTPIN (-7675 2325) $PN 86
J 2
(-7685 2335);
DISPLAY 0.680851 (-7685 2335);
PAINT MONO (-7685 2335);
FORCEPROP 0 LASTPIN (-7675 2275) $PN 87
J 2
(-7685 2285);
DISPLAY 0.680851 (-7685 2285);
PAINT MONO (-7685 2285);
FORCEPROP 0 LASTPIN (-7675 4925) $PN 74
J 2
(-7685 4935);
DISPLAY 0.680851 (-7685 4935);
PAINT MONO (-7685 4935);
FORCEPROP 0 LASTPIN (-7675 4875) $PN 227
J 2
(-7685 4885);
DISPLAY 0.680851 (-7685 4885);
PAINT MONO (-7685 4885);
FORCEPROP 0 LASTPIN (-7675 2875) $PN 147
J 2
(-7685 2885);
DISPLAY 0.680851 (-7685 2885);
PAINT MONO (-7685 2885);
FORCEPROP 0 LASTPIN (-7675 3425) $PN 207
J 2
(-7685 3435);
DISPLAY 0.680851 (-7685 3435);
PAINT MONO (-7685 3435);
FORCEPROP 0 LASTPIN (-7675 2475) $PN 2
J 2
(-7685 2485);
DISPLAY 0.680851 (-7685 2485);
PAINT MONO (-7685 2485);
FORCEPROP 0 LASTPIN (-7675 2525) $PN 144
J 2
(-7685 2535);
DISPLAY 0.680851 (-7685 2535);
PAINT MONO (-7685 2535);
FORCEPROP 0 LASTPIN (-7675 2575) $PN 149
J 2
(-7685 2585);
DISPLAY 0.680851 (-7685 2585);
PAINT MONO (-7685 2585);
FORCEPROP 0 LASTPIN (-7675 2625) $PN 150
J 2
(-7685 2635);
DISPLAY 0.680851 (-7685 2635);
PAINT MONO (-7685 2635);
FORCEPROP 0 LASTPIN (-7675 2675) $PN 220
J 2
(-7685 2685);
DISPLAY 0.680851 (-7685 2685);
PAINT MONO (-7685 2685);
FORCEPROP 0 LASTPIN (-7675 2725) $PN 231
J 2
(-7685 2735);
DISPLAY 0.680851 (-7685 2735);
PAINT MONO (-7685 2735);
FORCEPROP 0 LASTPIN (-7675 2775) $PN 232
J 2
(-7685 2785);
DISPLAY 0.680851 (-7685 2785);
PAINT MONO (-7685 2785);
FORCEPROP 0 LASTPIN (-7675 3275) $PN 3
J 2
(-7685 3285);
DISPLAY 0.680851 (-7685 3285);
PAINT MONO (-7685 3285);
FORCEPROP 2 LAST VALUE SCONN288_DDR506112002KQ
J 0
(-7525 6100);
DISPLAY 0.489362 (-7525 6100);
PAINT SKYBLUE (-7525 6100);
FORCEPROP 2 LAST PART_TYPE SMLF
J 0
(-7525 6150);
DISPLAY 1.021277 (-7525 6150);
FORCEPROP 1 LAST MATERIAL IO
J 0
(-7525 5900);
DISPLAY 0.468085 (-7525 5900);
PAINT SKYBLUE (-7525 5900);
FORCEPROP 1 LAST CDS_LMAN_SYM_OUTLINE -450,1900,450,-1850
J 0
(-7075 3975);
DISPLAY 0.468085 (-7075 3975);
PAINT GREEN (-7075 3975);
DISPLAY INVISIBLE (-7075 3975);
FORCEPROP 1 LAST NEEDS_NO_SIZE TRUE
J 0
(-7075 3975);
DISPLAY 0.723404 (-7075 3975);
PAINT GREEN (-7075 3975);
DISPLAY INVISIBLE (-7075 3975);
FORCEPROP 2 LAST CDS_LIB pure_quanta
J 0
(-7075 3975);
DISPLAY INVISIBLE (-7075 3975);
FORCEPROP 1 LAST PATH I350
J 0
(-7075 3975);
DISPLAY 0.723404 (-7075 3975);
PAINT GREEN (-7075 3975);
DISPLAY INVISIBLE (-7075 3975);
FORCEPROP 1 LAST PART_NUMBER DFHST8FS479
J 0
(-7525 5975);
DISPLAY 0.468085 (-7525 5975);
PAINT SKYBLUE (-7525 5975);
DISPLAY INVISIBLE (-7525 5975);
FORCEADD SCONN288_DDR506112002KQ..3
(-1400 4050);
FORCEPROP 1 LAST LOCATION J17
J 0
(-1850 6025);
DISPLAY 0.468085 (-1850 6025);
PAINT SKYBLUE (-1850 6025);
FORCEPROP 0 LAST $SEC 3
J 0
(-1850 6175);
DISPLAY 0.680851 (-1850 6175);
PAINT MONO (-1850 6175);
DISPLAY INVISIBLE (-1850 6175);
FORCEPROP 2 LAST CDS_SEC 3
J 0
(-1850 6175);
DISPLAY 1.021277 (-1850 6175);
DISPLAY INVISIBLE (-1850 6175);
FORCEPROP 0 LASTPIN (-800 2450) $PN G1
J 0
(-790 2460);
DISPLAY 0.680851 (-790 2460);
PAINT MONO (-790 2460);
FORCEPROP 0 LASTPIN (-800 2400) $PN G2
J 0
(-790 2410);
DISPLAY 0.680851 (-790 2410);
PAINT MONO (-790 2410);
FORCEPROP 0 LASTPIN (-800 2350) $PN G3
J 0
(-790 2360);
DISPLAY 0.680851 (-790 2360);
PAINT MONO (-790 2360);
FORCEPROP 0 LASTPIN (-2000 5600) $PN 1
J 2
(-2010 5610);
DISPLAY 0.680851 (-2010 5610);
PAINT MONO (-2010 5610);
FORCEPROP 0 LASTPIN (-2000 5650) $PN 145
J 2
(-2010 5660);
DISPLAY 0.680851 (-2010 5660);
PAINT MONO (-2010 5660);
FORCEPROP 0 LASTPIN (-2000 5700) $PN 146
J 2
(-2010 5710);
DISPLAY 0.680851 (-2010 5710);
PAINT MONO (-2010 5710);
FORCEPROP 0 LASTPIN (-800 2550) $PN 6
J 0
(-790 2560);
DISPLAY 0.680851 (-790 2560);
PAINT MONO (-790 2560);
FORCEPROP 0 LASTPIN (-800 2600) $PN 8
J 0
(-790 2610);
DISPLAY 0.680851 (-790 2610);
PAINT MONO (-790 2610);
FORCEPROP 0 LASTPIN (-800 2650) $PN 10
J 0
(-790 2660);
DISPLAY 0.680851 (-790 2660);
PAINT MONO (-790 2660);
FORCEPROP 0 LASTPIN (-800 2700) $PN 13
J 0
(-790 2710);
DISPLAY 0.680851 (-790 2710);
PAINT MONO (-790 2710);
FORCEPROP 0 LASTPIN (-800 2750) $PN 15
J 0
(-790 2760);
DISPLAY 0.680851 (-790 2760);
PAINT MONO (-790 2760);
FORCEPROP 0 LASTPIN (-800 2800) $PN 17
J 0
(-790 2810);
DISPLAY 0.680851 (-790 2810);
PAINT MONO (-790 2810);
FORCEPROP 0 LASTPIN (-800 2850) $PN 19
J 0
(-790 2860);
DISPLAY 0.680851 (-790 2860);
PAINT MONO (-790 2860);
FORCEPROP 0 LASTPIN (-800 2900) $PN 21
J 0
(-790 2910);
DISPLAY 0.680851 (-790 2910);
PAINT MONO (-790 2910);
FORCEPROP 0 LASTPIN (-800 2950) $PN 24
J 0
(-790 2960);
DISPLAY 0.680851 (-790 2960);
PAINT MONO (-790 2960);
FORCEPROP 0 LASTPIN (-800 3000) $PN 26
J 0
(-790 3010);
DISPLAY 0.680851 (-790 3010);
PAINT MONO (-790 3010);
FORCEPROP 0 LASTPIN (-800 3050) $PN 28
J 0
(-790 3060);
DISPLAY 0.680851 (-790 3060);
PAINT MONO (-790 3060);
FORCEPROP 0 LASTPIN (-800 3100) $PN 30
J 0
(-790 3110);
DISPLAY 0.680851 (-790 3110);
PAINT MONO (-790 3110);
FORCEPROP 0 LASTPIN (-800 3150) $PN 32
J 0
(-790 3160);
DISPLAY 0.680851 (-790 3160);
PAINT MONO (-790 3160);
FORCEPROP 0 LASTPIN (-800 3200) $PN 35
J 0
(-790 3210);
DISPLAY 0.680851 (-790 3210);
PAINT MONO (-790 3210);
FORCEPROP 0 LASTPIN (-800 3250) $PN 37
J 0
(-790 3260);
DISPLAY 0.680851 (-790 3260);
PAINT MONO (-790 3260);
FORCEPROP 0 LASTPIN (-800 3300) $PN 39
J 0
(-790 3310);
DISPLAY 0.680851 (-790 3310);
PAINT MONO (-790 3310);
FORCEPROP 0 LASTPIN (-800 3350) $PN 41
J 0
(-790 3360);
DISPLAY 0.680851 (-790 3360);
PAINT MONO (-790 3360);
FORCEPROP 0 LASTPIN (-800 3400) $PN 43
J 0
(-790 3410);
DISPLAY 0.680851 (-790 3410);
PAINT MONO (-790 3410);
FORCEPROP 0 LASTPIN (-800 3450) $PN 46
J 0
(-790 3460);
DISPLAY 0.680851 (-790 3460);
PAINT MONO (-790 3460);
FORCEPROP 0 LASTPIN (-800 3500) $PN 48
J 0
(-790 3510);
DISPLAY 0.680851 (-790 3510);
PAINT MONO (-790 3510);
FORCEPROP 0 LASTPIN (-800 3550) $PN 50
J 0
(-790 3560);
DISPLAY 0.680851 (-790 3560);
PAINT MONO (-790 3560);
FORCEPROP 0 LASTPIN (-800 3600) $PN 52
J 0
(-790 3610);
DISPLAY 0.680851 (-790 3610);
PAINT MONO (-790 3610);
FORCEPROP 0 LASTPIN (-800 3650) $PN 54
J 0
(-790 3660);
DISPLAY 0.680851 (-790 3660);
PAINT MONO (-790 3660);
FORCEPROP 0 LASTPIN (-800 3700) $PN 57
J 0
(-790 3710);
DISPLAY 0.680851 (-790 3710);
PAINT MONO (-790 3710);
FORCEPROP 0 LASTPIN (-800 3750) $PN 59
J 0
(-790 3760);
DISPLAY 0.680851 (-790 3760);
PAINT MONO (-790 3760);
FORCEPROP 0 LASTPIN (-800 3800) $PN 61
J 0
(-790 3810);
DISPLAY 0.680851 (-790 3810);
PAINT MONO (-790 3810);
FORCEPROP 0 LASTPIN (-800 3850) $PN 63
J 0
(-790 3860);
DISPLAY 0.680851 (-790 3860);
PAINT MONO (-790 3860);
FORCEPROP 0 LASTPIN (-800 3900) $PN 65
J 0
(-790 3910);
DISPLAY 0.680851 (-790 3910);
PAINT MONO (-790 3910);
FORCEPROP 0 LASTPIN (-800 3950) $PN 67
J 0
(-790 3960);
DISPLAY 0.680851 (-790 3960);
PAINT MONO (-790 3960);
FORCEPROP 0 LASTPIN (-800 4000) $PN 69
J 0
(-790 4010);
DISPLAY 0.680851 (-790 4010);
PAINT MONO (-790 4010);
FORCEPROP 0 LASTPIN (-800 4050) $PN 71
J 0
(-790 4060);
DISPLAY 0.680851 (-790 4060);
PAINT MONO (-790 4060);
FORCEPROP 0 LASTPIN (-800 4100) $PN 73
J 0
(-790 4110);
DISPLAY 0.680851 (-790 4110);
PAINT MONO (-790 4110);
FORCEPROP 0 LASTPIN (-800 4150) $PN 75
J 0
(-790 4160);
DISPLAY 0.680851 (-790 4160);
PAINT MONO (-790 4160);
FORCEPROP 0 LASTPIN (-800 4200) $PN 77
J 0
(-790 4210);
DISPLAY 0.680851 (-790 4210);
PAINT MONO (-790 4210);
FORCEPROP 0 LASTPIN (-800 4250) $PN 79
J 0
(-790 4260);
DISPLAY 0.680851 (-790 4260);
PAINT MONO (-790 4260);
FORCEPROP 0 LASTPIN (-800 4300) $PN 81
J 0
(-790 4310);
DISPLAY 0.680851 (-790 4310);
PAINT MONO (-790 4310);
FORCEPROP 0 LASTPIN (-800 4350) $PN 83
J 0
(-790 4360);
DISPLAY 0.680851 (-790 4360);
PAINT MONO (-790 4360);
FORCEPROP 0 LASTPIN (-800 4400) $PN 85
J 0
(-790 4410);
DISPLAY 0.680851 (-790 4410);
PAINT MONO (-790 4410);
FORCEPROP 0 LASTPIN (-800 4450) $PN 88
J 0
(-790 4460);
DISPLAY 0.680851 (-790 4460);
PAINT MONO (-790 4460);
FORCEPROP 0 LASTPIN (-800 4500) $PN 90
J 0
(-790 4510);
DISPLAY 0.680851 (-790 4510);
PAINT MONO (-790 4510);
FORCEPROP 0 LASTPIN (-800 4550) $PN 92
J 0
(-790 4560);
DISPLAY 0.680851 (-790 4560);
PAINT MONO (-790 4560);
FORCEPROP 0 LASTPIN (-800 4600) $PN 95
J 0
(-790 4610);
DISPLAY 0.680851 (-790 4610);
PAINT MONO (-790 4610);
FORCEPROP 0 LASTPIN (-800 4650) $PN 97
J 0
(-790 4660);
DISPLAY 0.680851 (-790 4660);
PAINT MONO (-790 4660);
FORCEPROP 0 LASTPIN (-800 4700) $PN 99
J 0
(-790 4710);
DISPLAY 0.680851 (-790 4710);
PAINT MONO (-790 4710);
FORCEPROP 0 LASTPIN (-800 4750) $PN 101
J 0
(-790 4760);
DISPLAY 0.680851 (-790 4760);
PAINT MONO (-790 4760);
FORCEPROP 0 LASTPIN (-800 4800) $PN 103
J 0
(-790 4810);
DISPLAY 0.680851 (-790 4810);
PAINT MONO (-790 4810);
FORCEPROP 0 LASTPIN (-800 4850) $PN 106
J 0
(-790 4860);
DISPLAY 0.680851 (-790 4860);
PAINT MONO (-790 4860);
FORCEPROP 0 LASTPIN (-800 4900) $PN 108
J 0
(-790 4910);
DISPLAY 0.680851 (-790 4910);
PAINT MONO (-790 4910);
FORCEPROP 0 LASTPIN (-800 4950) $PN 110
J 0
(-790 4960);
DISPLAY 0.680851 (-790 4960);
PAINT MONO (-790 4960);
FORCEPROP 0 LASTPIN (-800 5000) $PN 112
J 0
(-790 5010);
DISPLAY 0.680851 (-790 5010);
PAINT MONO (-790 5010);
FORCEPROP 0 LASTPIN (-800 5050) $PN 114
J 0
(-790 5060);
DISPLAY 0.680851 (-790 5060);
PAINT MONO (-790 5060);
FORCEPROP 0 LASTPIN (-800 5100) $PN 117
J 0
(-790 5110);
DISPLAY 0.680851 (-790 5110);
PAINT MONO (-790 5110);
FORCEPROP 0 LASTPIN (-800 5150) $PN 119
J 0
(-790 5160);
DISPLAY 0.680851 (-790 5160);
PAINT MONO (-790 5160);
FORCEPROP 0 LASTPIN (-800 5200) $PN 121
J 0
(-790 5210);
DISPLAY 0.680851 (-790 5210);
PAINT MONO (-790 5210);
FORCEPROP 0 LASTPIN (-800 5250) $PN 123
J 0
(-790 5260);
DISPLAY 0.680851 (-790 5260);
PAINT MONO (-790 5260);
FORCEPROP 0 LASTPIN (-800 5300) $PN 125
J 0
(-790 5310);
DISPLAY 0.680851 (-790 5310);
PAINT MONO (-790 5310);
FORCEPROP 0 LASTPIN (-800 5350) $PN 128
J 0
(-790 5360);
DISPLAY 0.680851 (-790 5360);
PAINT MONO (-790 5360);
FORCEPROP 0 LASTPIN (-800 5400) $PN 130
J 0
(-790 5410);
DISPLAY 0.680851 (-790 5410);
PAINT MONO (-790 5410);
FORCEPROP 0 LASTPIN (-800 5450) $PN 132
J 0
(-790 5460);
DISPLAY 0.680851 (-790 5460);
PAINT MONO (-790 5460);
FORCEPROP 0 LASTPIN (-800 5500) $PN 134
J 0
(-790 5510);
DISPLAY 0.680851 (-790 5510);
PAINT MONO (-790 5510);
FORCEPROP 0 LASTPIN (-800 5550) $PN 136
J 0
(-790 5560);
DISPLAY 0.680851 (-790 5560);
PAINT MONO (-790 5560);
FORCEPROP 0 LASTPIN (-800 5600) $PN 139
J 0
(-790 5610);
DISPLAY 0.680851 (-790 5610);
PAINT MONO (-790 5610);
FORCEPROP 0 LASTPIN (-800 5650) $PN 141
J 0
(-790 5660);
DISPLAY 0.680851 (-790 5660);
PAINT MONO (-790 5660);
FORCEPROP 0 LASTPIN (-800 5700) $PN 143
J 0
(-790 5710);
DISPLAY 0.680851 (-790 5710);
PAINT MONO (-790 5710);
FORCEPROP 0 LASTPIN (-2000 2450) $PN 151
J 2
(-2010 2460);
DISPLAY 0.680851 (-2010 2460);
PAINT MONO (-2010 2460);
FORCEPROP 0 LASTPIN (-2000 2500) $PN 153
J 2
(-2010 2510);
DISPLAY 0.680851 (-2010 2510);
PAINT MONO (-2010 2510);
FORCEPROP 0 LASTPIN (-2000 2550) $PN 155
J 2
(-2010 2560);
DISPLAY 0.680851 (-2010 2560);
PAINT MONO (-2010 2560);
FORCEPROP 0 LASTPIN (-2000 2600) $PN 158
J 2
(-2010 2610);
DISPLAY 0.680851 (-2010 2610);
PAINT MONO (-2010 2610);
FORCEPROP 0 LASTPIN (-2000 2650) $PN 160
J 2
(-2010 2660);
DISPLAY 0.680851 (-2010 2660);
PAINT MONO (-2010 2660);
FORCEPROP 0 LASTPIN (-2000 2700) $PN 162
J 2
(-2010 2710);
DISPLAY 0.680851 (-2010 2710);
PAINT MONO (-2010 2710);
FORCEPROP 0 LASTPIN (-2000 2750) $PN 164
J 2
(-2010 2760);
DISPLAY 0.680851 (-2010 2760);
PAINT MONO (-2010 2760);
FORCEPROP 0 LASTPIN (-2000 2800) $PN 166
J 2
(-2010 2810);
DISPLAY 0.680851 (-2010 2810);
PAINT MONO (-2010 2810);
FORCEPROP 0 LASTPIN (-2000 2850) $PN 169
J 2
(-2010 2860);
DISPLAY 0.680851 (-2010 2860);
PAINT MONO (-2010 2860);
FORCEPROP 0 LASTPIN (-2000 2900) $PN 171
J 2
(-2010 2910);
DISPLAY 0.680851 (-2010 2910);
PAINT MONO (-2010 2910);
FORCEPROP 0 LASTPIN (-2000 2950) $PN 173
J 2
(-2010 2960);
DISPLAY 0.680851 (-2010 2960);
PAINT MONO (-2010 2960);
FORCEPROP 0 LASTPIN (-2000 3000) $PN 175
J 2
(-2010 3010);
DISPLAY 0.680851 (-2010 3010);
PAINT MONO (-2010 3010);
FORCEPROP 0 LASTPIN (-2000 3050) $PN 177
J 2
(-2010 3060);
DISPLAY 0.680851 (-2010 3060);
PAINT MONO (-2010 3060);
FORCEPROP 0 LASTPIN (-2000 3100) $PN 180
J 2
(-2010 3110);
DISPLAY 0.680851 (-2010 3110);
PAINT MONO (-2010 3110);
FORCEPROP 0 LASTPIN (-2000 3150) $PN 182
J 2
(-2010 3160);
DISPLAY 0.680851 (-2010 3160);
PAINT MONO (-2010 3160);
FORCEPROP 0 LASTPIN (-2000 3200) $PN 184
J 2
(-2010 3210);
DISPLAY 0.680851 (-2010 3210);
PAINT MONO (-2010 3210);
FORCEPROP 0 LASTPIN (-2000 3250) $PN 186
J 2
(-2010 3260);
DISPLAY 0.680851 (-2010 3260);
PAINT MONO (-2010 3260);
FORCEPROP 0 LASTPIN (-2000 3300) $PN 188
J 2
(-2010 3310);
DISPLAY 0.680851 (-2010 3310);
PAINT MONO (-2010 3310);
FORCEPROP 0 LASTPIN (-2000 3350) $PN 191
J 2
(-2010 3360);
DISPLAY 0.680851 (-2010 3360);
PAINT MONO (-2010 3360);
FORCEPROP 0 LASTPIN (-2000 3400) $PN 193
J 2
(-2010 3410);
DISPLAY 0.680851 (-2010 3410);
PAINT MONO (-2010 3410);
FORCEPROP 0 LASTPIN (-2000 3450) $PN 195
J 2
(-2010 3460);
DISPLAY 0.680851 (-2010 3460);
PAINT MONO (-2010 3460);
FORCEPROP 0 LASTPIN (-2000 3500) $PN 197
J 2
(-2010 3510);
DISPLAY 0.680851 (-2010 3510);
PAINT MONO (-2010 3510);
FORCEPROP 0 LASTPIN (-2000 3550) $PN 199
J 2
(-2010 3560);
DISPLAY 0.680851 (-2010 3560);
PAINT MONO (-2010 3560);
FORCEPROP 0 LASTPIN (-2000 3600) $PN 202
J 2
(-2010 3610);
DISPLAY 0.680851 (-2010 3610);
PAINT MONO (-2010 3610);
FORCEPROP 0 LASTPIN (-2000 3650) $PN 204
J 2
(-2010 3660);
DISPLAY 0.680851 (-2010 3660);
PAINT MONO (-2010 3660);
FORCEPROP 0 LASTPIN (-2000 3700) $PN 206
J 2
(-2010 3710);
DISPLAY 0.680851 (-2010 3710);
PAINT MONO (-2010 3710);
FORCEPROP 0 LASTPIN (-2000 3750) $PN 208
J 2
(-2010 3760);
DISPLAY 0.680851 (-2010 3760);
PAINT MONO (-2010 3760);
FORCEPROP 0 LASTPIN (-2000 3800) $PN 210
J 2
(-2010 3810);
DISPLAY 0.680851 (-2010 3810);
PAINT MONO (-2010 3810);
FORCEPROP 0 LASTPIN (-2000 3850) $PN 212
J 2
(-2010 3860);
DISPLAY 0.680851 (-2010 3860);
PAINT MONO (-2010 3860);
FORCEPROP 0 LASTPIN (-2000 3900) $PN 214
J 2
(-2010 3910);
DISPLAY 0.680851 (-2010 3910);
PAINT MONO (-2010 3910);
FORCEPROP 0 LASTPIN (-2000 3950) $PN 216
J 2
(-2010 3960);
DISPLAY 0.680851 (-2010 3960);
PAINT MONO (-2010 3960);
FORCEPROP 0 LASTPIN (-2000 4000) $PN 219
J 2
(-2010 4010);
DISPLAY 0.680851 (-2010 4010);
PAINT MONO (-2010 4010);
FORCEPROP 0 LASTPIN (-2000 4050) $PN 222
J 2
(-2010 4060);
DISPLAY 0.680851 (-2010 4060);
PAINT MONO (-2010 4060);
FORCEPROP 0 LASTPIN (-2000 4100) $PN 224
J 2
(-2010 4110);
DISPLAY 0.680851 (-2010 4110);
PAINT MONO (-2010 4110);
FORCEPROP 0 LASTPIN (-2000 4150) $PN 226
J 2
(-2010 4160);
DISPLAY 0.680851 (-2010 4160);
PAINT MONO (-2010 4160);
FORCEPROP 0 LASTPIN (-2000 4200) $PN 228
J 2
(-2010 4210);
DISPLAY 0.680851 (-2010 4210);
PAINT MONO (-2010 4210);
FORCEPROP 0 LASTPIN (-2000 4250) $PN 230
J 2
(-2010 4260);
DISPLAY 0.680851 (-2010 4260);
PAINT MONO (-2010 4260);
FORCEPROP 0 LASTPIN (-2000 4300) $PN 233
J 2
(-2010 4310);
DISPLAY 0.680851 (-2010 4310);
PAINT MONO (-2010 4310);
FORCEPROP 0 LASTPIN (-2000 4350) $PN 235
J 2
(-2010 4360);
DISPLAY 0.680851 (-2010 4360);
PAINT MONO (-2010 4360);
FORCEPROP 0 LASTPIN (-2000 4400) $PN 237
J 2
(-2010 4410);
DISPLAY 0.680851 (-2010 4410);
PAINT MONO (-2010 4410);
FORCEPROP 0 LASTPIN (-2000 4450) $PN 240
J 2
(-2010 4460);
DISPLAY 0.680851 (-2010 4460);
PAINT MONO (-2010 4460);
FORCEPROP 0 LASTPIN (-2000 4500) $PN 242
J 2
(-2010 4510);
DISPLAY 0.680851 (-2010 4510);
PAINT MONO (-2010 4510);
FORCEPROP 0 LASTPIN (-2000 4550) $PN 244
J 2
(-2010 4560);
DISPLAY 0.680851 (-2010 4560);
PAINT MONO (-2010 4560);
FORCEPROP 0 LASTPIN (-2000 4600) $PN 246
J 2
(-2010 4610);
DISPLAY 0.680851 (-2010 4610);
PAINT MONO (-2010 4610);
FORCEPROP 0 LASTPIN (-2000 4650) $PN 248
J 2
(-2010 4660);
DISPLAY 0.680851 (-2010 4660);
PAINT MONO (-2010 4660);
FORCEPROP 0 LASTPIN (-2000 4700) $PN 251
J 2
(-2010 4710);
DISPLAY 0.680851 (-2010 4710);
PAINT MONO (-2010 4710);
FORCEPROP 0 LASTPIN (-2000 4750) $PN 253
J 2
(-2010 4760);
DISPLAY 0.680851 (-2010 4760);
PAINT MONO (-2010 4760);
FORCEPROP 0 LASTPIN (-2000 4800) $PN 255
J 2
(-2010 4810);
DISPLAY 0.680851 (-2010 4810);
PAINT MONO (-2010 4810);
FORCEPROP 0 LASTPIN (-2000 4850) $PN 257
J 2
(-2010 4860);
DISPLAY 0.680851 (-2010 4860);
PAINT MONO (-2010 4860);
FORCEPROP 0 LASTPIN (-2000 4900) $PN 259
J 2
(-2010 4910);
DISPLAY 0.680851 (-2010 4910);
PAINT MONO (-2010 4910);
FORCEPROP 0 LASTPIN (-2000 4950) $PN 262
J 2
(-2010 4960);
DISPLAY 0.680851 (-2010 4960);
PAINT MONO (-2010 4960);
FORCEPROP 0 LASTPIN (-2000 5000) $PN 264
J 2
(-2010 5010);
DISPLAY 0.680851 (-2010 5010);
PAINT MONO (-2010 5010);
FORCEPROP 0 LASTPIN (-2000 5050) $PN 266
J 2
(-2010 5060);
DISPLAY 0.680851 (-2010 5060);
PAINT MONO (-2010 5060);
FORCEPROP 0 LASTPIN (-2000 5100) $PN 268
J 2
(-2010 5110);
DISPLAY 0.680851 (-2010 5110);
PAINT MONO (-2010 5110);
FORCEPROP 0 LASTPIN (-2000 5150) $PN 270
J 2
(-2010 5160);
DISPLAY 0.680851 (-2010 5160);
PAINT MONO (-2010 5160);
FORCEPROP 0 LASTPIN (-2000 5200) $PN 273
J 2
(-2010 5210);
DISPLAY 0.680851 (-2010 5210);
PAINT MONO (-2010 5210);
FORCEPROP 0 LASTPIN (-2000 5250) $PN 275
J 2
(-2010 5260);
DISPLAY 0.680851 (-2010 5260);
PAINT MONO (-2010 5260);
FORCEPROP 0 LASTPIN (-2000 5300) $PN 277
J 2
(-2010 5310);
DISPLAY 0.680851 (-2010 5310);
PAINT MONO (-2010 5310);
FORCEPROP 0 LASTPIN (-2000 5350) $PN 279
J 2
(-2010 5360);
DISPLAY 0.680851 (-2010 5360);
PAINT MONO (-2010 5360);
FORCEPROP 0 LASTPIN (-2000 5400) $PN 281
J 2
(-2010 5410);
DISPLAY 0.680851 (-2010 5410);
PAINT MONO (-2010 5410);
FORCEPROP 0 LASTPIN (-2000 5450) $PN 284
J 2
(-2010 5460);
DISPLAY 0.680851 (-2010 5460);
PAINT MONO (-2010 5460);
FORCEPROP 0 LASTPIN (-2000 5500) $PN 286
J 2
(-2010 5510);
DISPLAY 0.680851 (-2010 5510);
PAINT MONO (-2010 5510);
FORCEPROP 0 LASTPIN (-2000 5550) $PN 288
J 2
(-2010 5560);
DISPLAY 0.680851 (-2010 5560);
PAINT MONO (-2010 5560);
FORCEPROP 2 LAST PART_TYPE SMLF
J 0
(-1850 6125);
DISPLAY 1.021277 (-1850 6125);
FORCEPROP 2 LAST VALUE SCONN288_DDR506112002KQ
J 0
(-1850 6075);
DISPLAY 0.489362 (-1850 6075);
PAINT SKYBLUE (-1850 6075);
FORCEPROP 1 LAST MATERIAL IO
J 0
(-1850 5875);
DISPLAY 0.468085 (-1850 5875);
PAINT SKYBLUE (-1850 5875);
FORCEPROP 1 LAST CDS_LMAN_SYM_OUTLINE -450,1800,450,-1750
J 0
(-1400 4050);
DISPLAY 0.468085 (-1400 4050);
PAINT GREEN (-1400 4050);
DISPLAY INVISIBLE (-1400 4050);
FORCEPROP 1 LAST NEEDS_NO_SIZE TRUE
J 0
(-1400 4050);
DISPLAY 0.723404 (-1400 4050);
PAINT GREEN (-1400 4050);
DISPLAY INVISIBLE (-1400 4050);
FORCEPROP 2 LAST CDS_LIB pure_quanta
J 0
(-1400 4050);
DISPLAY INVISIBLE (-1400 4050);
FORCEPROP 1 LAST PATH I352
J 0
(-1400 4050);
DISPLAY 0.723404 (-1400 4050);
PAINT GREEN (-1400 4050);
DISPLAY INVISIBLE (-1400 4050);
FORCEPROP 1 LAST PART_NUMBER DFHST8FS479
J 0
(-1850 5950);
DISPLAY 0.468085 (-1850 5950);
PAINT SKYBLUE (-1850 5950);
DISPLAY INVISIBLE (-1850 5950);
FORCEADD OFFPAGE..5
(-8525 3375);
FORCEPROP 2 LAST $XR0 12 
J 0
(-8779 3375);
DISPLAY 0.638298 (-8779 3375);
PAINT MONO (-8779 3375);
FORCEPROP 2 LAST CDS_LIB mstr_standard
J 0
(-8525 3375);
DISPLAY INVISIBLE (-8525 3375);
FORCEPROP 1 LAST OFFPAGE TRUE
J 0
(-8200 3250);
DISPLAY 0.872340 (-8200 3250);
PAINT GREEN (-8200 3250);
DISPLAY INVISIBLE (-8200 3250);
FORCEPROP 1 LAST COMMENT_BODY TRUE
J 0
(-8425 3300);
DISPLAY 0.872340 (-8425 3300);
PAINT GREEN (-8425 3300);
DISPLAY INVISIBLE (-8425 3300);
FORCEPROP 2 LAST PATH I353
J 0
(-8475 3450);
DISPLAY 1.021277 (-8475 3450);
DISPLAY INVISIBLE (-8475 3450);
FORCEADD GND..1
(-8925 3300);
FORCEPROP 3 LASTPIN (-8925 3350) SIG_NAME GND\g
J 0
(-8915 3360);
DISPLAY 0.659574 (-8915 3360);
PAINT MONO (-8915 3360);
DISPLAY INVISIBLE (-8915 3360);
FORCEPROP 2 LAST BOM_COST MEM
J 0
(-8900 3425);
DISPLAY 0.659574 (-8900 3425);
DISPLAY INVISIBLE (-8900 3425);
FORCEPROP 1 LAST SIZE 1B
J 0
(-8850 3250);
DISPLAY 0.723404 (-8850 3250);
PAINT GREEN (-8850 3250);
DISPLAY INVISIBLE (-8850 3250);
FORCEPROP 2 LAST CDS_LIB mstr_symbols
J 0
(-8925 3300);
DISPLAY 0.808511 (-8925 3300);
DISPLAY INVISIBLE (-8925 3300);
FORCEPROP 1 LAST VOLTAGE 0
J 0
(-8945 3395);
DISPLAY 0.829787 (-8945 3395);
PAINT SKYBLUE (-8945 3395);
DISPLAY INVISIBLE (-8945 3395);
FORCEPROP 2 LAST ROOM MEM_EFGH_DECOUPLING_CAPS
J 0
(-8900 3375);
DISPLAY 0.659574 (-8900 3375);
PAINT RED (-8900 3375);
DISPLAY INVISIBLE (-8900 3375);
FORCEPROP 1 LAST BODY_TYPE PLUMBING
J 0
(-8970 3257);
DISPLAY 0.276596 (-8970 3257);
PAINT GREEN (-8970 3257);
DISPLAY INVISIBLE (-8970 3257);
FORCEPROP 1 LAST HDL_POWER GND
J 0
(-8925 3450);
DISPLAY 0.723404 (-8925 3450);
PAINT GREEN (-8925 3450);
DISPLAY INVISIBLE (-8925 3450);
FORCEPROP 1 LAST PATH I361
J 0
(-8850 3300);
DISPLAY 0.872340 (-8850 3300);
PAINT AQUA (-8850 3300);
DISPLAY INVISIBLE (-8850 3300);
FORCEADD Q_CAP..1
R 2
(-8925 3525);
FORCEPROP 1 LAST LOCATION C96
J 2
(-8975 3625);
DISPLAY 0.489362 (-8975 3625);
PAINT SKYBLUE (-8975 3625);
FORCEPROP 0 LAST $SEC 1
J 0
(-8975 3675);
DISPLAY 0.680851 (-8975 3675);
PAINT MONO (-8975 3675);
DISPLAY INVISIBLE (-8975 3675);
FORCEPROP 0 LAST CDS_SEC 1
J 0
(-8975 3675);
DISPLAY 1.021277 (-8975 3675);
DISPLAY INVISIBLE (-8975 3675);
FORCEPROP 1 LASTPIN (-8925 3625) $PN 1
J 2
(-8935 3605);
DISPLAY 0.489362 (-8935 3605);
PAINT MONO (-8935 3605);
FORCEPROP 1 LASTPIN (-8925 3425) $PN 2
J 2
(-8935 3405);
DISPLAY 0.489362 (-8935 3405);
PAINT MONO (-8935 3405);
FORCEPROP 1 LAST MATERIAL X7R
J 2
(-8975 3425);
DISPLAY 0.489362 (-8975 3425);
PAINT SKYBLUE (-8975 3425);
FORCEPROP 1 LAST TOLERANCE 10%
J 2
(-8975 3475);
DISPLAY 0.489362 (-8975 3475);
PAINT SKYBLUE (-8975 3475);
FORCEPROP 1 LAST VALUE 0.1UF
J 2
(-8975 3575);
DISPLAY 0.489362 (-8975 3575);
PAINT SKYBLUE (-8975 3575);
FORCEPROP 1 LAST PACK_TYPE 0402
J 2
(-8975 3325);
DISPLAY 0.489362 (-8975 3325);
PAINT SKYBLUE (-8975 3325);
FORCEPROP 1 LAST VOLTAGE 25V
J 2
(-8975 3525);
DISPLAY 0.489362 (-8975 3525);
PAINT SKYBLUE (-8975 3525);
FORCEPROP 2 LAST CDS_LIB pure_quanta
J 0
(-8925 3525);
DISPLAY INVISIBLE (-8925 3525);
FORCEPROP 0 LAST BOM_COST MEM
J 2
(-8980 3670);
DISPLAY 0.595745 (-8980 3670);
PAINT MONO (-8980 3670);
DISPLAY INVISIBLE (-8980 3670);
FORCEPROP 2 LAST ROOM 
J 2
(-8980 3670);
DISPLAY 0.595745 (-8980 3670);
PAINT RED (-8980 3670);
DISPLAY INVISIBLE (-8980 3670);
FORCEPROP 1 LAST PATH I362
J 2
(-8975 3675);
DISPLAY 0.978723 (-8975 3675);
PAINT WHITE (-8975 3675);
DISPLAY INVISIBLE (-8975 3675);
FORCEPROP 1 LAST PART_NUMBER CH4104K1B00
J 2
(-8975 3375);
DISPLAY 0.489362 (-8975 3375);
PAINT SKYBLUE (-8975 3375);
DISPLAY INVISIBLE (-8975 3375);
FORCEADD OFFPAGE..6
(-9175 2475);
FORCEPROP 2 LAST $XR4 91 
J 0
(-9454 2511);
DISPLAY 0.638298 (-9454 2511);
PAINT MONO (-9454 2511);
FORCEPROP 2 LAST $XR3 90 
J 0
(-9544 2439);
DISPLAY 0.638298 (-9544 2439);
PAINT MONO (-9544 2439);
FORCEPROP 2 LAST $XR2 89 
J 0
(-9454 2439);
DISPLAY 0.638298 (-9454 2439);
PAINT MONO (-9454 2439);
FORCEPROP 2 LAST $XR1 87 
J 0
(-9544 2475);
DISPLAY 0.638298 (-9544 2475);
PAINT MONO (-9544 2475);
FORCEPROP 2 LAST $XR0 86 
J 0
(-9454 2475);
DISPLAY 0.638298 (-9454 2475);
PAINT MONO (-9454 2475);
FORCEPROP 2 LAST CDS_LIB mstr_standard
J 0
(-9175 2475);
DISPLAY 0.808511 (-9175 2475);
DISPLAY INVISIBLE (-9175 2475);
FORCEPROP 1 LAST OFFPAGE TRUE
J 0
(-8850 2350);
DISPLAY 0.872340 (-8850 2350);
PAINT GREEN (-8850 2350);
DISPLAY INVISIBLE (-8850 2350);
FORCEPROP 1 LAST COMMENT_BODY TRUE
J 0
(-9075 2400);
DISPLAY 0.872340 (-9075 2400);
PAINT GREEN (-9075 2400);
DISPLAY INVISIBLE (-9075 2400);
FORCEPROP 2 LAST PATH I363
J 0
(-9125 2550);
DISPLAY 1.021277 (-9125 2550);
DISPLAY INVISIBLE (-9125 2550);
FORCEADD Q_RES..1
R 2
(-8675 2475);
FORCEPROP 1 LAST LOCATION R293
J 2
(-8650 2500);
DISPLAY 0.489362 (-8650 2500);
PAINT SKYBLUE (-8650 2500);
FORCEPROP 0 LAST $SEC 1
J 0
(-8650 2550);
DISPLAY 0.680851 (-8650 2550);
PAINT MONO (-8650 2550);
DISPLAY INVISIBLE (-8650 2550);
FORCEPROP 0 LAST CDS_SEC 1
J 0
(-8650 2550);
DISPLAY 1.021277 (-8650 2550);
DISPLAY INVISIBLE (-8650 2550);
FORCEPROP 1 LASTPIN (-8575 2475) $PN 1
J 2
(-8587 2487);
DISPLAY 0.489362 (-8587 2487);
PAINT MONO (-8587 2487);
FORCEPROP 1 LASTPIN (-8775 2475) $PN 2
J 2
(-8737 2487);
DISPLAY 0.489362 (-8737 2487);
PAINT MONO (-8737 2487);
FORCEPROP 1 LAST VALUE 1K
J 0
(-8675 2425);
DISPLAY 0.489362 (-8675 2425);
PAINT SKYBLUE (-8675 2425);
FORCEPROP 1 LAST TOLERANCE 1%
J 2
(-8550 2450);
DISPLAY 0.489362 (-8550 2450);
PAINT SKYBLUE (-8550 2450);
DISPLAY INVISIBLE (-8550 2450);
FORCEPROP 2 LAST BOM_COST MEM
J 0
(-8700 2625);
DISPLAY 0.744681 (-8700 2625);
PAINT WHITE (-8700 2625);
DISPLAY INVISIBLE (-8700 2625);
FORCEPROP 2 LAST CDS_LIB pure_quanta
J 0
(-8675 2475);
DISPLAY INVISIBLE (-8675 2475);
FORCEPROP 1 LAST WATTAGE 1/16W
J 0
(-8600 2400);
DISPLAY 0.489362 (-8600 2400);
PAINT SKYBLUE (-8600 2400);
DISPLAY INVISIBLE (-8600 2400);
FORCEPROP 1 LAST MATERIAL CHIP
J 0
(-8850 2450);
DISPLAY 0.489362 (-8850 2450);
PAINT SKYBLUE (-8850 2450);
DISPLAY INVISIBLE (-8850 2450);
FORCEPROP 1 LAST PACK_TYPE 0402LF
J 0
(-8850 2400);
DISPLAY 0.489362 (-8850 2400);
PAINT SKYBLUE (-8850 2400);
DISPLAY INVISIBLE (-8850 2400);
FORCEPROP 2 LAST ROOM 
J 0
(-8700 2575);
DISPLAY 0.744681 (-8700 2575);
PAINT RED (-8700 2575);
DISPLAY INVISIBLE (-8700 2575);
FORCEPROP 1 LAST PATH I364
J 2
(-8625 2625);
DISPLAY 0.978723 (-8625 2625);
PAINT WHITE (-8625 2625);
DISPLAY INVISIBLE (-8625 2625);
FORCEPROP 1 LAST PART_NUMBER CS21002FB06
J 0
(-8775 2525);
DISPLAY 0.489362 (-8775 2525);
PAINT SKYBLUE (-8775 2525);
DISPLAY INVISIBLE (-8775 2525);
FORCEADD Q_RES..2
(-8550 2625);
FORCEPROP 1 LAST LOCATION R91
J 0
(-8505 2750);
DISPLAY 0.489362 (-8505 2750);
PAINT SKYBLUE (-8505 2750);
FORCEPROP 0 LAST $SEC 1
J 0
(-8500 2800);
DISPLAY 0.680851 (-8500 2800);
PAINT MONO (-8500 2800);
DISPLAY INVISIBLE (-8500 2800);
FORCEPROP 0 LAST CDS_SEC 1
J 0
(-8500 2800);
DISPLAY 1.021277 (-8500 2800);
DISPLAY INVISIBLE (-8500 2800);
FORCEPROP 1 LASTPIN (-8550 2725) $PN 1
J 0
(-8545 2687);
DISPLAY 0.489362 (-8545 2687);
PAINT MONO (-8545 2687);
FORCEPROP 1 LASTPIN (-8550 2525) $PN 2
J 0
(-8545 2535);
DISPLAY 0.489362 (-8545 2535);
PAINT MONO (-8545 2535);
FORCEPROP 1 LAST TOLERANCE 1%
J 0
(-8500 2675);
DISPLAY 0.489362 (-8500 2675);
PAINT SKYBLUE (-8500 2675);
FORCEPROP 1 LAST PACK_TYPE 0402LF
J 0
(-8500 2575);
DISPLAY 0.489362 (-8500 2575);
PAINT SKYBLUE (-8500 2575);
FORCEPROP 1 LAST VALUE 1K
J 0
(-8505 2700);
DISPLAY 0.489362 (-8505 2700);
PAINT SKYBLUE (-8505 2700);
FORCEPROP 1 LAST WATTAGE 1/16W
J 0
(-8500 2650);
DISPLAY 0.489362 (-8500 2650);
PAINT SKYBLUE (-8500 2650);
FORCEPROP 1 LAST MATERIAL EMPTY
J 0
(-8500 2625);
DISPLAY 0.489362 (-8500 2625);
PAINT RED (-8500 2625);
FORCEPROP 2 LAST CDS_LIB pure_quanta
J 2
(-8550 2625);
DISPLAY INVISIBLE (-8550 2625);
FORCEPROP 2 LAST BOM_COST MEM
J 0
(-8500 2800);
DISPLAY 0.808511 (-8500 2800);
DISPLAY INVISIBLE (-8500 2800);
FORCEPROP 2 LAST ROOM 
J 0
(-8500 2850);
DISPLAY 0.808511 (-8500 2850);
PAINT RED (-8500 2850);
DISPLAY INVISIBLE (-8500 2850);
FORCEPROP 1 LAST PATH I365
J 0
(-8500 2800);
DISPLAY 0.978723 (-8500 2800);
PAINT WHITE (-8500 2800);
DISPLAY INVISIBLE (-8500 2800);
FORCEPROP 1 LAST PART_NUMBER CS21002FB06
J 0
(-8500 2600);
DISPLAY 0.489362 (-8500 2600);
PAINT SKYBLUE (-8500 2600);
DISPLAY INVISIBLE (-8500 2600);
FORCEADD VCC_CORE..1
(-8550 2800);
FORCEPROP 3 LASTPIN (-8550 2750) SIG_NAME P3V3\g
J 0
(-8540 2760);
DISPLAY 0.659574 (-8540 2760);
PAINT MONO (-8540 2760);
DISPLAY INVISIBLE (-8540 2760);
FORCEPROP 1 LAST HDL_POWER P3V3
J 1
(-8550 2850);
DISPLAY 0.489362 (-8550 2850);
PAINT GREEN (-8550 2850);
FORCEPROP 2 LAST CDS_LIB mstr_symbols
J 0
(-8550 2800);
DISPLAY INVISIBLE (-8550 2800);
FORCEPROP 0 LAST VOLTAGE 3.3
J 0
(-8825 2950);
DISPLAY 1.021277 (-8825 2950);
PAINT SKYBLUE (-8825 2950);
DISPLAY INVISIBLE (-8825 2950);
FORCEPROP 2 LAST ROOM PVCCINFAON_CPU0_CTRL
J 0
(-8550 2900);
DISPLAY 0.808511 (-8550 2900);
PAINT RED (-8550 2900);
DISPLAY INVISIBLE (-8550 2900);
FORCEPROP 1 LAST PATH I366
J 0
(-8500 2825);
DISPLAY 0.872340 (-8500 2825);
PAINT AQUA (-8500 2825);
DISPLAY INVISIBLE (-8500 2825);
FORCEADD OFFPAGE..2
(-2725 3900);
FORCEPROP 2 LAST $XR0 12 
J 0
(-2536 3900);
DISPLAY 0.638298 (-2536 3900);
PAINT MONO (-2536 3900);
FORCEPROP 2 LAST CDS_LIB mstr_standard
J 0
(-2725 3900);
DISPLAY 0.723404 (-2725 3900);
PAINT MONO (-2725 3900);
DISPLAY INVISIBLE (-2725 3900);
FORCEPROP 1 LAST OFFPAGE TRUE
J 0
(-2400 3775);
DISPLAY 0.723404 (-2400 3775);
PAINT GREEN (-2400 3775);
DISPLAY INVISIBLE (-2400 3775);
FORCEPROP 1 LAST COMMENT_BODY TRUE
J 0
(-2770 3805);
DISPLAY 0.872340 (-2770 3805);
PAINT GREEN (-2770 3805);
DISPLAY INVISIBLE (-2770 3805);
FORCEPROP 2 LAST PATH I367
J 0
(-2525 3950);
DISPLAY 0.680851 (-2525 3950);
DISPLAY INVISIBLE (-2525 3950);
FORCEADD OFFPAGE..2
(-2725 3950);
FORCEPROP 2 LAST $XR0 12 
J 0
(-2536 3950);
DISPLAY 0.638298 (-2536 3950);
PAINT MONO (-2536 3950);
FORCEPROP 2 LAST CDS_LIB mstr_standard
J 0
(-2725 3950);
DISPLAY 0.723404 (-2725 3950);
PAINT MONO (-2725 3950);
DISPLAY INVISIBLE (-2725 3950);
FORCEPROP 1 LAST OFFPAGE TRUE
J 0
(-2400 3825);
DISPLAY 0.723404 (-2400 3825);
PAINT GREEN (-2400 3825);
DISPLAY INVISIBLE (-2400 3825);
FORCEPROP 1 LAST COMMENT_BODY TRUE
J 0
(-2770 3855);
DISPLAY 0.872340 (-2770 3855);
PAINT GREEN (-2770 3855);
DISPLAY INVISIBLE (-2770 3855);
FORCEPROP 2 LAST PATH I368
J 0
(-2525 4000);
DISPLAY 0.680851 (-2525 4000);
DISPLAY INVISIBLE (-2525 4000);
FORCEADD OFFPAGE..2
(-2725 4950);
FORCEPROP 2 LAST $XR0 12 
J 0
(-2536 4950);
DISPLAY 0.638298 (-2536 4950);
PAINT MONO (-2536 4950);
FORCEPROP 2 LAST CDS_LIB mstr_standard
J 0
(-2725 4950);
DISPLAY 0.723404 (-2725 4950);
PAINT MONO (-2725 4950);
DISPLAY INVISIBLE (-2725 4950);
FORCEPROP 1 LAST OFFPAGE TRUE
J 0
(-2400 4825);
DISPLAY 0.723404 (-2400 4825);
PAINT GREEN (-2400 4825);
DISPLAY INVISIBLE (-2400 4825);
FORCEPROP 1 LAST COMMENT_BODY TRUE
J 0
(-2770 4855);
DISPLAY 0.872340 (-2770 4855);
PAINT GREEN (-2770 4855);
DISPLAY INVISIBLE (-2770 4855);
FORCEPROP 2 LAST PATH I369
J 0
(-2525 5000);
DISPLAY 0.680851 (-2525 5000);
DISPLAY INVISIBLE (-2525 5000);
FORCEADD OFFPAGE..2
(-2725 5000);
FORCEPROP 2 LAST $XR0 12 
J 0
(-2536 5000);
DISPLAY 0.638298 (-2536 5000);
PAINT MONO (-2536 5000);
FORCEPROP 2 LAST CDS_LIB mstr_standard
J 0
(-2725 5000);
DISPLAY 0.723404 (-2725 5000);
PAINT MONO (-2725 5000);
DISPLAY INVISIBLE (-2725 5000);
FORCEPROP 1 LAST OFFPAGE TRUE
J 0
(-2400 4875);
DISPLAY 0.723404 (-2400 4875);
PAINT GREEN (-2400 4875);
DISPLAY INVISIBLE (-2400 4875);
FORCEPROP 1 LAST COMMENT_BODY TRUE
J 0
(-2770 4905);
DISPLAY 0.872340 (-2770 4905);
PAINT GREEN (-2770 4905);
DISPLAY INVISIBLE (-2770 4905);
FORCEPROP 2 LAST PATH I370
J 0
(-2525 5050);
DISPLAY 0.680851 (-2525 5050);
DISPLAY INVISIBLE (-2525 5050);
FORCEADD TAP..1
(-3525 4900);
FORCEPROP 3 LASTPIN (-3575 4900) SIG_NAME M_C_CPU0_SA_DQS_DN<9>
J 0
(-3565 4910);
DISPLAY 0.659574 (-3565 4910);
PAINT MONO (-3565 4910);
DISPLAY INVISIBLE (-3565 4910);
FORCEPROP 1 LASTPIN (-3575 4900) BN 9
J 0
(-3587 4908);
DISPLAY 0.489362 (-3587 4908);
PAINT GREEN (-3587 4908);
FORCEPROP 2 LAST CDS_LIB mstr_standard
J 0
(-3525 4900);
DISPLAY 0.723404 (-3525 4900);
PAINT MONO (-3525 4900);
DISPLAY INVISIBLE (-3525 4900);
FORCEPROP 1 LAST BODY_TYPE PLUMBING
J 0
(-3525 4950);
DISPLAY 0.872340 (-3525 4950);
PAINT GREEN (-3525 4950);
DISPLAY INVISIBLE (-3525 4950);
FORCEPROP 1 LAST HDL_TAP TRUE
J 0
(-3200 4775);
DISPLAY 0.872340 (-3200 4775);
DISPLAY INVISIBLE (-3200 4775);
FORCEPROP 1 LAST PATH I371
J 0
(-3527 4900);
DISPLAY 0.872340 (-3527 4900);
PAINT GREEN (-3527 4900);
DISPLAY INVISIBLE (-3527 4900);
FORCEADD TAP..1
(-3525 4700);
FORCEPROP 3 LASTPIN (-3575 4700) SIG_NAME M_C_CPU0_SA_DQS_DN<7>
J 0
(-3565 4710);
DISPLAY 0.659574 (-3565 4710);
PAINT MONO (-3565 4710);
DISPLAY INVISIBLE (-3565 4710);
FORCEPROP 1 LASTPIN (-3575 4700) BN 7
J 0
(-3587 4708);
DISPLAY 0.489362 (-3587 4708);
PAINT GREEN (-3587 4708);
FORCEPROP 2 LAST CDS_LIB mstr_standard
J 0
(-3525 4700);
DISPLAY 0.723404 (-3525 4700);
PAINT MONO (-3525 4700);
DISPLAY INVISIBLE (-3525 4700);
FORCEPROP 1 LAST BODY_TYPE PLUMBING
J 0
(-3525 4750);
DISPLAY 0.872340 (-3525 4750);
PAINT GREEN (-3525 4750);
DISPLAY INVISIBLE (-3525 4750);
FORCEPROP 1 LAST HDL_TAP TRUE
J 0
(-3200 4575);
DISPLAY 0.872340 (-3200 4575);
DISPLAY INVISIBLE (-3200 4575);
FORCEPROP 1 LAST PATH I372
J 0
(-3527 4700);
DISPLAY 0.872340 (-3527 4700);
PAINT GREEN (-3527 4700);
DISPLAY INVISIBLE (-3527 4700);
FORCEADD TAP..1
(-3525 4800);
FORCEPROP 3 LASTPIN (-3575 4800) SIG_NAME M_C_CPU0_SA_DQS_DN<8>
J 0
(-3565 4810);
DISPLAY 0.659574 (-3565 4810);
PAINT MONO (-3565 4810);
DISPLAY INVISIBLE (-3565 4810);
FORCEPROP 1 LASTPIN (-3575 4800) BN 8
J 0
(-3587 4808);
DISPLAY 0.489362 (-3587 4808);
PAINT GREEN (-3587 4808);
FORCEPROP 2 LAST CDS_LIB mstr_standard
J 0
(-3525 4800);
DISPLAY 0.723404 (-3525 4800);
PAINT MONO (-3525 4800);
DISPLAY INVISIBLE (-3525 4800);
FORCEPROP 1 LAST BODY_TYPE PLUMBING
J 0
(-3525 4850);
DISPLAY 0.872340 (-3525 4850);
PAINT GREEN (-3525 4850);
DISPLAY INVISIBLE (-3525 4850);
FORCEPROP 1 LAST HDL_TAP TRUE
J 0
(-3200 4675);
DISPLAY 0.872340 (-3200 4675);
DISPLAY INVISIBLE (-3200 4675);
FORCEPROP 1 LAST PATH I373
J 0
(-3527 4800);
DISPLAY 0.872340 (-3527 4800);
PAINT GREEN (-3527 4800);
DISPLAY INVISIBLE (-3527 4800);
FORCEADD TAP..1
(-3525 4600);
FORCEPROP 3 LASTPIN (-3575 4600) SIG_NAME M_C_CPU0_SA_DQS_DN<6>
J 0
(-3565 4610);
DISPLAY 0.659574 (-3565 4610);
PAINT MONO (-3565 4610);
DISPLAY INVISIBLE (-3565 4610);
FORCEPROP 1 LASTPIN (-3575 4600) BN 6
J 0
(-3587 4608);
DISPLAY 0.489362 (-3587 4608);
PAINT GREEN (-3587 4608);
FORCEPROP 2 LAST CDS_LIB mstr_standard
J 0
(-3525 4600);
DISPLAY 0.723404 (-3525 4600);
PAINT MONO (-3525 4600);
DISPLAY INVISIBLE (-3525 4600);
FORCEPROP 1 LAST BODY_TYPE PLUMBING
J 0
(-3525 4650);
DISPLAY 0.872340 (-3525 4650);
PAINT GREEN (-3525 4650);
DISPLAY INVISIBLE (-3525 4650);
FORCEPROP 1 LAST HDL_TAP TRUE
J 0
(-3200 4475);
DISPLAY 0.872340 (-3200 4475);
DISPLAY INVISIBLE (-3200 4475);
FORCEPROP 1 LAST PATH I374
J 0
(-3527 4600);
DISPLAY 0.872340 (-3527 4600);
PAINT GREEN (-3527 4600);
DISPLAY INVISIBLE (-3527 4600);
FORCEADD TAP..1
(-3525 4500);
FORCEPROP 3 LASTPIN (-3575 4500) SIG_NAME M_C_CPU0_SA_DQS_DN<5>
J 0
(-3565 4510);
DISPLAY 0.659574 (-3565 4510);
PAINT MONO (-3565 4510);
DISPLAY INVISIBLE (-3565 4510);
FORCEPROP 1 LASTPIN (-3575 4500) BN 5
J 0
(-3587 4508);
DISPLAY 0.489362 (-3587 4508);
PAINT GREEN (-3587 4508);
FORCEPROP 2 LAST CDS_LIB mstr_standard
J 0
(-3525 4500);
DISPLAY 0.723404 (-3525 4500);
PAINT MONO (-3525 4500);
DISPLAY INVISIBLE (-3525 4500);
FORCEPROP 1 LAST BODY_TYPE PLUMBING
J 0
(-3525 4550);
DISPLAY 0.872340 (-3525 4550);
PAINT GREEN (-3525 4550);
DISPLAY INVISIBLE (-3525 4550);
FORCEPROP 1 LAST HDL_TAP TRUE
J 0
(-3200 4375);
DISPLAY 0.872340 (-3200 4375);
DISPLAY INVISIBLE (-3200 4375);
FORCEPROP 1 LAST PATH I375
J 0
(-3527 4500);
DISPLAY 0.872340 (-3527 4500);
PAINT GREEN (-3527 4500);
DISPLAY INVISIBLE (-3527 4500);
FORCEADD TAP..1
(-3525 4400);
FORCEPROP 3 LASTPIN (-3575 4400) SIG_NAME M_C_CPU0_SA_DQS_DN<4>
J 0
(-3565 4410);
DISPLAY 0.659574 (-3565 4410);
PAINT MONO (-3565 4410);
DISPLAY INVISIBLE (-3565 4410);
FORCEPROP 1 LASTPIN (-3575 4400) BN 4
J 0
(-3587 4408);
DISPLAY 0.489362 (-3587 4408);
PAINT GREEN (-3587 4408);
FORCEPROP 2 LAST CDS_LIB mstr_standard
J 0
(-3525 4400);
DISPLAY 0.723404 (-3525 4400);
PAINT MONO (-3525 4400);
DISPLAY INVISIBLE (-3525 4400);
FORCEPROP 1 LAST BODY_TYPE PLUMBING
J 0
(-3525 4450);
DISPLAY 0.872340 (-3525 4450);
PAINT GREEN (-3525 4450);
DISPLAY INVISIBLE (-3525 4450);
FORCEPROP 1 LAST HDL_TAP TRUE
J 0
(-3200 4275);
DISPLAY 0.872340 (-3200 4275);
DISPLAY INVISIBLE (-3200 4275);
FORCEPROP 1 LAST PATH I376
J 0
(-3527 4400);
DISPLAY 0.872340 (-3527 4400);
PAINT GREEN (-3527 4400);
DISPLAY INVISIBLE (-3527 4400);
FORCEADD TAP..1
(-3525 4300);
FORCEPROP 3 LASTPIN (-3575 4300) SIG_NAME M_C_CPU0_SA_DQS_DN<3>
J 0
(-3565 4310);
DISPLAY 0.659574 (-3565 4310);
PAINT MONO (-3565 4310);
DISPLAY INVISIBLE (-3565 4310);
FORCEPROP 1 LASTPIN (-3575 4300) BN 3
J 0
(-3587 4308);
DISPLAY 0.489362 (-3587 4308);
PAINT GREEN (-3587 4308);
FORCEPROP 2 LAST CDS_LIB mstr_standard
J 0
(-3525 4300);
DISPLAY 0.723404 (-3525 4300);
PAINT MONO (-3525 4300);
DISPLAY INVISIBLE (-3525 4300);
FORCEPROP 1 LAST BODY_TYPE PLUMBING
J 0
(-3525 4350);
DISPLAY 0.872340 (-3525 4350);
PAINT GREEN (-3525 4350);
DISPLAY INVISIBLE (-3525 4350);
FORCEPROP 1 LAST HDL_TAP TRUE
J 0
(-3200 4175);
DISPLAY 0.872340 (-3200 4175);
DISPLAY INVISIBLE (-3200 4175);
FORCEPROP 1 LAST PATH I377
J 0
(-3527 4300);
DISPLAY 0.872340 (-3527 4300);
PAINT GREEN (-3527 4300);
DISPLAY INVISIBLE (-3527 4300);
FORCEADD TAP..1
(-3525 4200);
FORCEPROP 3 LASTPIN (-3575 4200) SIG_NAME M_C_CPU0_SA_DQS_DN<2>
J 0
(-3565 4210);
DISPLAY 0.659574 (-3565 4210);
PAINT MONO (-3565 4210);
DISPLAY INVISIBLE (-3565 4210);
FORCEPROP 1 LASTPIN (-3575 4200) BN 2
J 0
(-3587 4208);
DISPLAY 0.489362 (-3587 4208);
PAINT GREEN (-3587 4208);
FORCEPROP 2 LAST CDS_LIB mstr_standard
J 0
(-3525 4200);
DISPLAY 0.723404 (-3525 4200);
PAINT MONO (-3525 4200);
DISPLAY INVISIBLE (-3525 4200);
FORCEPROP 1 LAST BODY_TYPE PLUMBING
J 0
(-3525 4250);
DISPLAY 0.872340 (-3525 4250);
PAINT GREEN (-3525 4250);
DISPLAY INVISIBLE (-3525 4250);
FORCEPROP 1 LAST HDL_TAP TRUE
J 0
(-3200 4075);
DISPLAY 0.872340 (-3200 4075);
DISPLAY INVISIBLE (-3200 4075);
FORCEPROP 1 LAST PATH I378
J 0
(-3527 4200);
DISPLAY 0.872340 (-3527 4200);
PAINT GREEN (-3527 4200);
DISPLAY INVISIBLE (-3527 4200);
FORCEADD TAP..1
(-3525 4100);
FORCEPROP 3 LASTPIN (-3575 4100) SIG_NAME M_C_CPU0_SA_DQS_DN<1>
J 0
(-3565 4110);
DISPLAY 0.659574 (-3565 4110);
PAINT MONO (-3565 4110);
DISPLAY INVISIBLE (-3565 4110);
FORCEPROP 1 LASTPIN (-3575 4100) BN 1
J 0
(-3587 4108);
DISPLAY 0.489362 (-3587 4108);
PAINT GREEN (-3587 4108);
FORCEPROP 2 LAST CDS_LIB mstr_standard
J 0
(-3525 4100);
DISPLAY 0.723404 (-3525 4100);
PAINT MONO (-3525 4100);
DISPLAY INVISIBLE (-3525 4100);
FORCEPROP 1 LAST BODY_TYPE PLUMBING
J 0
(-3525 4150);
DISPLAY 0.872340 (-3525 4150);
PAINT GREEN (-3525 4150);
DISPLAY INVISIBLE (-3525 4150);
FORCEPROP 1 LAST HDL_TAP TRUE
J 0
(-3200 3975);
DISPLAY 0.872340 (-3200 3975);
DISPLAY INVISIBLE (-3200 3975);
FORCEPROP 1 LAST PATH I379
J 0
(-3527 4100);
DISPLAY 0.872340 (-3527 4100);
PAINT GREEN (-3527 4100);
DISPLAY INVISIBLE (-3527 4100);
FORCEADD TAP..1
(-3525 4000);
FORCEPROP 3 LASTPIN (-3575 4000) SIG_NAME M_C_CPU0_SA_DQS_DN<0>
J 0
(-3565 4010);
DISPLAY 0.659574 (-3565 4010);
PAINT MONO (-3565 4010);
DISPLAY INVISIBLE (-3565 4010);
FORCEPROP 1 LASTPIN (-3575 4000) BN 0
J 0
(-3587 4008);
DISPLAY 0.489362 (-3587 4008);
PAINT GREEN (-3587 4008);
FORCEPROP 2 LAST CDS_LIB mstr_standard
J 0
(-3525 4000);
DISPLAY 0.723404 (-3525 4000);
PAINT MONO (-3525 4000);
DISPLAY INVISIBLE (-3525 4000);
FORCEPROP 1 LAST BODY_TYPE PLUMBING
J 0
(-3525 4050);
DISPLAY 0.872340 (-3525 4050);
PAINT GREEN (-3525 4050);
DISPLAY INVISIBLE (-3525 4050);
FORCEPROP 1 LAST HDL_TAP TRUE
J 0
(-3200 3875);
DISPLAY 0.872340 (-3200 3875);
DISPLAY INVISIBLE (-3200 3875);
FORCEPROP 1 LAST PATH I380
J 0
(-3527 4000);
DISPLAY 0.872340 (-3527 4000);
PAINT GREEN (-3527 4000);
DISPLAY INVISIBLE (-3527 4000);
FORCEADD TAP..1
(-3525 3850);
FORCEPROP 3 LASTPIN (-3575 3850) SIG_NAME M_C_CPU0_SB_DQS_DN<9>
J 0
(-3565 3860);
DISPLAY 0.659574 (-3565 3860);
PAINT MONO (-3565 3860);
DISPLAY INVISIBLE (-3565 3860);
FORCEPROP 1 LASTPIN (-3575 3850) BN 9
J 0
(-3587 3858);
DISPLAY 0.489362 (-3587 3858);
PAINT GREEN (-3587 3858);
FORCEPROP 2 LAST CDS_LIB mstr_standard
J 0
(-3525 3850);
DISPLAY 0.723404 (-3525 3850);
PAINT MONO (-3525 3850);
DISPLAY INVISIBLE (-3525 3850);
FORCEPROP 1 LAST BODY_TYPE PLUMBING
J 0
(-3525 3900);
DISPLAY 0.872340 (-3525 3900);
PAINT GREEN (-3525 3900);
DISPLAY INVISIBLE (-3525 3900);
FORCEPROP 1 LAST HDL_TAP TRUE
J 0
(-3200 3725);
DISPLAY 0.872340 (-3200 3725);
DISPLAY INVISIBLE (-3200 3725);
FORCEPROP 1 LAST PATH I381
J 0
(-3527 3850);
DISPLAY 0.872340 (-3527 3850);
PAINT GREEN (-3527 3850);
DISPLAY INVISIBLE (-3527 3850);
FORCEADD TAP..1
(-3525 3750);
FORCEPROP 3 LASTPIN (-3575 3750) SIG_NAME M_C_CPU0_SB_DQS_DN<8>
J 0
(-3565 3760);
DISPLAY 0.659574 (-3565 3760);
PAINT MONO (-3565 3760);
DISPLAY INVISIBLE (-3565 3760);
FORCEPROP 1 LASTPIN (-3575 3750) BN 8
J 0
(-3587 3758);
DISPLAY 0.489362 (-3587 3758);
PAINT GREEN (-3587 3758);
FORCEPROP 2 LAST CDS_LIB mstr_standard
J 0
(-3525 3750);
DISPLAY 0.723404 (-3525 3750);
PAINT MONO (-3525 3750);
DISPLAY INVISIBLE (-3525 3750);
FORCEPROP 1 LAST BODY_TYPE PLUMBING
J 0
(-3525 3800);
DISPLAY 0.872340 (-3525 3800);
PAINT GREEN (-3525 3800);
DISPLAY INVISIBLE (-3525 3800);
FORCEPROP 1 LAST HDL_TAP TRUE
J 0
(-3200 3625);
DISPLAY 0.872340 (-3200 3625);
DISPLAY INVISIBLE (-3200 3625);
FORCEPROP 1 LAST PATH I382
J 0
(-3527 3750);
DISPLAY 0.872340 (-3527 3750);
PAINT GREEN (-3527 3750);
DISPLAY INVISIBLE (-3527 3750);
FORCEADD TAP..1
(-3525 3550);
FORCEPROP 3 LASTPIN (-3575 3550) SIG_NAME M_C_CPU0_SB_DQS_DN<6>
J 0
(-3565 3560);
DISPLAY 0.659574 (-3565 3560);
PAINT MONO (-3565 3560);
DISPLAY INVISIBLE (-3565 3560);
FORCEPROP 1 LASTPIN (-3575 3550) BN 6
J 0
(-3587 3558);
DISPLAY 0.489362 (-3587 3558);
PAINT GREEN (-3587 3558);
FORCEPROP 2 LAST CDS_LIB mstr_standard
J 0
(-3525 3550);
DISPLAY 0.723404 (-3525 3550);
PAINT MONO (-3525 3550);
DISPLAY INVISIBLE (-3525 3550);
FORCEPROP 1 LAST BODY_TYPE PLUMBING
J 0
(-3525 3600);
DISPLAY 0.872340 (-3525 3600);
PAINT GREEN (-3525 3600);
DISPLAY INVISIBLE (-3525 3600);
FORCEPROP 1 LAST HDL_TAP TRUE
J 0
(-3200 3425);
DISPLAY 0.872340 (-3200 3425);
DISPLAY INVISIBLE (-3200 3425);
FORCEPROP 1 LAST PATH I383
J 0
(-3527 3550);
DISPLAY 0.872340 (-3527 3550);
PAINT GREEN (-3527 3550);
DISPLAY INVISIBLE (-3527 3550);
FORCEADD TAP..1
(-3525 3650);
FORCEPROP 3 LASTPIN (-3575 3650) SIG_NAME M_C_CPU0_SB_DQS_DN<7>
J 0
(-3565 3660);
DISPLAY 0.659574 (-3565 3660);
PAINT MONO (-3565 3660);
DISPLAY INVISIBLE (-3565 3660);
FORCEPROP 1 LASTPIN (-3575 3650) BN 7
J 0
(-3587 3658);
DISPLAY 0.489362 (-3587 3658);
PAINT GREEN (-3587 3658);
FORCEPROP 2 LAST CDS_LIB mstr_standard
J 0
(-3525 3650);
DISPLAY 0.723404 (-3525 3650);
PAINT MONO (-3525 3650);
DISPLAY INVISIBLE (-3525 3650);
FORCEPROP 1 LAST BODY_TYPE PLUMBING
J 0
(-3525 3700);
DISPLAY 0.872340 (-3525 3700);
PAINT GREEN (-3525 3700);
DISPLAY INVISIBLE (-3525 3700);
FORCEPROP 1 LAST HDL_TAP TRUE
J 0
(-3200 3525);
DISPLAY 0.872340 (-3200 3525);
DISPLAY INVISIBLE (-3200 3525);
FORCEPROP 1 LAST PATH I384
J 0
(-3527 3650);
DISPLAY 0.872340 (-3527 3650);
PAINT GREEN (-3527 3650);
DISPLAY INVISIBLE (-3527 3650);
FORCEADD TAP..1
(-3525 3450);
FORCEPROP 3 LASTPIN (-3575 3450) SIG_NAME M_C_CPU0_SB_DQS_DN<5>
J 0
(-3565 3460);
DISPLAY 0.659574 (-3565 3460);
PAINT MONO (-3565 3460);
DISPLAY INVISIBLE (-3565 3460);
FORCEPROP 1 LASTPIN (-3575 3450) BN 5
J 0
(-3587 3458);
DISPLAY 0.489362 (-3587 3458);
PAINT GREEN (-3587 3458);
FORCEPROP 2 LAST CDS_LIB mstr_standard
J 0
(-3525 3450);
DISPLAY 0.723404 (-3525 3450);
PAINT MONO (-3525 3450);
DISPLAY INVISIBLE (-3525 3450);
FORCEPROP 1 LAST BODY_TYPE PLUMBING
J 0
(-3525 3500);
DISPLAY 0.872340 (-3525 3500);
PAINT GREEN (-3525 3500);
DISPLAY INVISIBLE (-3525 3500);
FORCEPROP 1 LAST HDL_TAP TRUE
J 0
(-3200 3325);
DISPLAY 0.872340 (-3200 3325);
DISPLAY INVISIBLE (-3200 3325);
FORCEPROP 1 LAST PATH I385
J 0
(-3527 3450);
DISPLAY 0.872340 (-3527 3450);
PAINT GREEN (-3527 3450);
DISPLAY INVISIBLE (-3527 3450);
FORCEADD TAP..1
(-3525 3350);
FORCEPROP 3 LASTPIN (-3575 3350) SIG_NAME M_C_CPU0_SB_DQS_DN<4>
J 0
(-3565 3360);
DISPLAY 0.659574 (-3565 3360);
PAINT MONO (-3565 3360);
DISPLAY INVISIBLE (-3565 3360);
FORCEPROP 1 LASTPIN (-3575 3350) BN 4
J 0
(-3587 3358);
DISPLAY 0.489362 (-3587 3358);
PAINT GREEN (-3587 3358);
FORCEPROP 2 LAST CDS_LIB mstr_standard
J 0
(-3525 3350);
DISPLAY 0.723404 (-3525 3350);
PAINT MONO (-3525 3350);
DISPLAY INVISIBLE (-3525 3350);
FORCEPROP 1 LAST BODY_TYPE PLUMBING
J 0
(-3525 3400);
DISPLAY 0.872340 (-3525 3400);
PAINT GREEN (-3525 3400);
DISPLAY INVISIBLE (-3525 3400);
FORCEPROP 1 LAST HDL_TAP TRUE
J 0
(-3200 3225);
DISPLAY 0.872340 (-3200 3225);
DISPLAY INVISIBLE (-3200 3225);
FORCEPROP 1 LAST PATH I386
J 0
(-3527 3350);
DISPLAY 0.872340 (-3527 3350);
PAINT GREEN (-3527 3350);
DISPLAY INVISIBLE (-3527 3350);
FORCEADD TAP..1
(-3525 3150);
FORCEPROP 3 LASTPIN (-3575 3150) SIG_NAME M_C_CPU0_SB_DQS_DN<2>
J 0
(-3565 3160);
DISPLAY 0.659574 (-3565 3160);
PAINT MONO (-3565 3160);
DISPLAY INVISIBLE (-3565 3160);
FORCEPROP 1 LASTPIN (-3575 3150) BN 2
J 0
(-3587 3158);
DISPLAY 0.489362 (-3587 3158);
PAINT GREEN (-3587 3158);
FORCEPROP 2 LAST CDS_LIB mstr_standard
J 0
(-3525 3150);
DISPLAY 0.723404 (-3525 3150);
PAINT MONO (-3525 3150);
DISPLAY INVISIBLE (-3525 3150);
FORCEPROP 1 LAST BODY_TYPE PLUMBING
J 0
(-3525 3200);
DISPLAY 0.872340 (-3525 3200);
PAINT GREEN (-3525 3200);
DISPLAY INVISIBLE (-3525 3200);
FORCEPROP 1 LAST HDL_TAP TRUE
J 0
(-3200 3025);
DISPLAY 0.872340 (-3200 3025);
DISPLAY INVISIBLE (-3200 3025);
FORCEPROP 1 LAST PATH I387
J 0
(-3527 3150);
DISPLAY 0.872340 (-3527 3150);
PAINT GREEN (-3527 3150);
DISPLAY INVISIBLE (-3527 3150);
FORCEADD TAP..1
(-3525 3250);
FORCEPROP 3 LASTPIN (-3575 3250) SIG_NAME M_C_CPU0_SB_DQS_DN<3>
J 0
(-3565 3260);
DISPLAY 0.659574 (-3565 3260);
PAINT MONO (-3565 3260);
DISPLAY INVISIBLE (-3565 3260);
FORCEPROP 1 LASTPIN (-3575 3250) BN 3
J 0
(-3587 3258);
DISPLAY 0.489362 (-3587 3258);
PAINT GREEN (-3587 3258);
FORCEPROP 2 LAST CDS_LIB mstr_standard
J 0
(-3525 3250);
DISPLAY 0.723404 (-3525 3250);
PAINT MONO (-3525 3250);
DISPLAY INVISIBLE (-3525 3250);
FORCEPROP 1 LAST BODY_TYPE PLUMBING
J 0
(-3525 3300);
DISPLAY 0.872340 (-3525 3300);
PAINT GREEN (-3525 3300);
DISPLAY INVISIBLE (-3525 3300);
FORCEPROP 1 LAST HDL_TAP TRUE
J 0
(-3200 3125);
DISPLAY 0.872340 (-3200 3125);
DISPLAY INVISIBLE (-3200 3125);
FORCEPROP 1 LAST PATH I388
J 0
(-3527 3250);
DISPLAY 0.872340 (-3527 3250);
PAINT GREEN (-3527 3250);
DISPLAY INVISIBLE (-3527 3250);
FORCEADD TAP..1
(-3525 3050);
FORCEPROP 3 LASTPIN (-3575 3050) SIG_NAME M_C_CPU0_SB_DQS_DN<1>
J 0
(-3565 3060);
DISPLAY 0.659574 (-3565 3060);
PAINT MONO (-3565 3060);
DISPLAY INVISIBLE (-3565 3060);
FORCEPROP 1 LASTPIN (-3575 3050) BN 1
J 0
(-3587 3058);
DISPLAY 0.489362 (-3587 3058);
PAINT GREEN (-3587 3058);
FORCEPROP 2 LAST CDS_LIB mstr_standard
J 0
(-3525 3050);
DISPLAY 0.723404 (-3525 3050);
PAINT MONO (-3525 3050);
DISPLAY INVISIBLE (-3525 3050);
FORCEPROP 1 LAST BODY_TYPE PLUMBING
J 0
(-3525 3100);
DISPLAY 0.872340 (-3525 3100);
PAINT GREEN (-3525 3100);
DISPLAY INVISIBLE (-3525 3100);
FORCEPROP 1 LAST HDL_TAP TRUE
J 0
(-3200 2925);
DISPLAY 0.872340 (-3200 2925);
DISPLAY INVISIBLE (-3200 2925);
FORCEPROP 1 LAST PATH I389
J 0
(-3527 3050);
DISPLAY 0.872340 (-3527 3050);
PAINT GREEN (-3527 3050);
DISPLAY INVISIBLE (-3527 3050);
FORCEADD TAP..1
(-3525 2950);
FORCEPROP 3 LASTPIN (-3575 2950) SIG_NAME M_C_CPU0_SB_DQS_DN<0>
J 0
(-3565 2960);
DISPLAY 0.659574 (-3565 2960);
PAINT MONO (-3565 2960);
DISPLAY INVISIBLE (-3565 2960);
FORCEPROP 1 LASTPIN (-3575 2950) BN 0
J 0
(-3587 2958);
DISPLAY 0.489362 (-3587 2958);
PAINT GREEN (-3587 2958);
FORCEPROP 2 LAST CDS_LIB mstr_standard
J 0
(-3525 2950);
DISPLAY 0.723404 (-3525 2950);
PAINT MONO (-3525 2950);
DISPLAY INVISIBLE (-3525 2950);
FORCEPROP 1 LAST BODY_TYPE PLUMBING
J 0
(-3525 3000);
DISPLAY 0.872340 (-3525 3000);
PAINT GREEN (-3525 3000);
DISPLAY INVISIBLE (-3525 3000);
FORCEPROP 1 LAST HDL_TAP TRUE
J 0
(-3200 2825);
DISPLAY 0.872340 (-3200 2825);
DISPLAY INVISIBLE (-3200 2825);
FORCEPROP 1 LAST PATH I390
J 0
(-3527 2950);
DISPLAY 0.872340 (-3527 2950);
PAINT GREEN (-3527 2950);
DISPLAY INVISIBLE (-3527 2950);
FORCEADD TAP..1
(-3725 4950);
FORCEPROP 3 LASTPIN (-3775 4950) SIG_NAME M_C_CPU0_SA_DQS_DP<9>
J 0
(-3765 4960);
DISPLAY 0.659574 (-3765 4960);
PAINT MONO (-3765 4960);
DISPLAY INVISIBLE (-3765 4960);
FORCEPROP 1 LASTPIN (-3775 4950) BN 9
J 0
(-3787 4958);
DISPLAY 0.489362 (-3787 4958);
PAINT GREEN (-3787 4958);
FORCEPROP 2 LAST CDS_LIB mstr_standard
J 0
(-3725 4950);
DISPLAY 0.723404 (-3725 4950);
PAINT MONO (-3725 4950);
DISPLAY INVISIBLE (-3725 4950);
FORCEPROP 1 LAST BODY_TYPE PLUMBING
J 0
(-3725 5000);
DISPLAY 0.872340 (-3725 5000);
PAINT GREEN (-3725 5000);
DISPLAY INVISIBLE (-3725 5000);
FORCEPROP 1 LAST HDL_TAP TRUE
J 0
(-3400 4825);
DISPLAY 0.872340 (-3400 4825);
DISPLAY INVISIBLE (-3400 4825);
FORCEPROP 1 LAST PATH I391
J 0
(-3727 4950);
DISPLAY 0.872340 (-3727 4950);
PAINT GREEN (-3727 4950);
DISPLAY INVISIBLE (-3727 4950);
FORCEADD TAP..1
(-3725 4850);
FORCEPROP 3 LASTPIN (-3775 4850) SIG_NAME M_C_CPU0_SA_DQS_DP<8>
J 0
(-3765 4860);
DISPLAY 0.659574 (-3765 4860);
PAINT MONO (-3765 4860);
DISPLAY INVISIBLE (-3765 4860);
FORCEPROP 1 LASTPIN (-3775 4850) BN 8
J 0
(-3787 4858);
DISPLAY 0.489362 (-3787 4858);
PAINT GREEN (-3787 4858);
FORCEPROP 2 LAST CDS_LIB mstr_standard
J 0
(-3725 4850);
DISPLAY 0.723404 (-3725 4850);
PAINT MONO (-3725 4850);
DISPLAY INVISIBLE (-3725 4850);
FORCEPROP 1 LAST BODY_TYPE PLUMBING
J 0
(-3725 4900);
DISPLAY 0.872340 (-3725 4900);
PAINT GREEN (-3725 4900);
DISPLAY INVISIBLE (-3725 4900);
FORCEPROP 1 LAST HDL_TAP TRUE
J 0
(-3400 4725);
DISPLAY 0.872340 (-3400 4725);
DISPLAY INVISIBLE (-3400 4725);
FORCEPROP 1 LAST PATH I392
J 0
(-3727 4850);
DISPLAY 0.872340 (-3727 4850);
PAINT GREEN (-3727 4850);
DISPLAY INVISIBLE (-3727 4850);
FORCEADD TAP..1
(-3725 4750);
FORCEPROP 3 LASTPIN (-3775 4750) SIG_NAME M_C_CPU0_SA_DQS_DP<7>
J 0
(-3765 4760);
DISPLAY 0.659574 (-3765 4760);
PAINT MONO (-3765 4760);
DISPLAY INVISIBLE (-3765 4760);
FORCEPROP 1 LASTPIN (-3775 4750) BN 7
J 0
(-3787 4758);
DISPLAY 0.489362 (-3787 4758);
PAINT GREEN (-3787 4758);
FORCEPROP 2 LAST CDS_LIB mstr_standard
J 0
(-3725 4750);
DISPLAY 0.723404 (-3725 4750);
PAINT MONO (-3725 4750);
DISPLAY INVISIBLE (-3725 4750);
FORCEPROP 1 LAST BODY_TYPE PLUMBING
J 0
(-3725 4800);
DISPLAY 0.872340 (-3725 4800);
PAINT GREEN (-3725 4800);
DISPLAY INVISIBLE (-3725 4800);
FORCEPROP 1 LAST HDL_TAP TRUE
J 0
(-3400 4625);
DISPLAY 0.872340 (-3400 4625);
DISPLAY INVISIBLE (-3400 4625);
FORCEPROP 1 LAST PATH I393
J 0
(-3727 4750);
DISPLAY 0.872340 (-3727 4750);
PAINT GREEN (-3727 4750);
DISPLAY INVISIBLE (-3727 4750);
FORCEADD TAP..1
(-3725 4550);
FORCEPROP 3 LASTPIN (-3775 4550) SIG_NAME M_C_CPU0_SA_DQS_DP<5>
J 0
(-3765 4560);
DISPLAY 0.659574 (-3765 4560);
PAINT MONO (-3765 4560);
DISPLAY INVISIBLE (-3765 4560);
FORCEPROP 1 LASTPIN (-3775 4550) BN 5
J 0
(-3787 4558);
DISPLAY 0.489362 (-3787 4558);
PAINT GREEN (-3787 4558);
FORCEPROP 2 LAST CDS_LIB mstr_standard
J 0
(-3725 4550);
DISPLAY 0.723404 (-3725 4550);
PAINT MONO (-3725 4550);
DISPLAY INVISIBLE (-3725 4550);
FORCEPROP 1 LAST BODY_TYPE PLUMBING
J 0
(-3725 4600);
DISPLAY 0.872340 (-3725 4600);
PAINT GREEN (-3725 4600);
DISPLAY INVISIBLE (-3725 4600);
FORCEPROP 1 LAST HDL_TAP TRUE
J 0
(-3400 4425);
DISPLAY 0.872340 (-3400 4425);
DISPLAY INVISIBLE (-3400 4425);
FORCEPROP 1 LAST PATH I394
J 0
(-3727 4550);
DISPLAY 0.872340 (-3727 4550);
PAINT GREEN (-3727 4550);
DISPLAY INVISIBLE (-3727 4550);
FORCEADD TAP..1
(-3725 4650);
FORCEPROP 3 LASTPIN (-3775 4650) SIG_NAME M_C_CPU0_SA_DQS_DP<6>
J 0
(-3765 4660);
DISPLAY 0.659574 (-3765 4660);
PAINT MONO (-3765 4660);
DISPLAY INVISIBLE (-3765 4660);
FORCEPROP 1 LASTPIN (-3775 4650) BN 6
J 0
(-3787 4658);
DISPLAY 0.489362 (-3787 4658);
PAINT GREEN (-3787 4658);
FORCEPROP 2 LAST CDS_LIB mstr_standard
J 0
(-3725 4650);
DISPLAY 0.723404 (-3725 4650);
PAINT MONO (-3725 4650);
DISPLAY INVISIBLE (-3725 4650);
FORCEPROP 1 LAST BODY_TYPE PLUMBING
J 0
(-3725 4700);
DISPLAY 0.872340 (-3725 4700);
PAINT GREEN (-3725 4700);
DISPLAY INVISIBLE (-3725 4700);
FORCEPROP 1 LAST HDL_TAP TRUE
J 0
(-3400 4525);
DISPLAY 0.872340 (-3400 4525);
DISPLAY INVISIBLE (-3400 4525);
FORCEPROP 1 LAST PATH I395
J 0
(-3727 4650);
DISPLAY 0.872340 (-3727 4650);
PAINT GREEN (-3727 4650);
DISPLAY INVISIBLE (-3727 4650);
FORCEADD TAP..1
(-3725 4450);
FORCEPROP 3 LASTPIN (-3775 4450) SIG_NAME M_C_CPU0_SA_DQS_DP<4>
J 0
(-3765 4460);
DISPLAY 0.659574 (-3765 4460);
PAINT MONO (-3765 4460);
DISPLAY INVISIBLE (-3765 4460);
FORCEPROP 1 LASTPIN (-3775 4450) BN 4
J 0
(-3787 4458);
DISPLAY 0.489362 (-3787 4458);
PAINT GREEN (-3787 4458);
FORCEPROP 2 LAST CDS_LIB mstr_standard
J 0
(-3725 4450);
DISPLAY 0.723404 (-3725 4450);
PAINT MONO (-3725 4450);
DISPLAY INVISIBLE (-3725 4450);
FORCEPROP 1 LAST BODY_TYPE PLUMBING
J 0
(-3725 4500);
DISPLAY 0.872340 (-3725 4500);
PAINT GREEN (-3725 4500);
DISPLAY INVISIBLE (-3725 4500);
FORCEPROP 1 LAST HDL_TAP TRUE
J 0
(-3400 4325);
DISPLAY 0.872340 (-3400 4325);
DISPLAY INVISIBLE (-3400 4325);
FORCEPROP 1 LAST PATH I396
J 0
(-3727 4450);
DISPLAY 0.872340 (-3727 4450);
PAINT GREEN (-3727 4450);
DISPLAY INVISIBLE (-3727 4450);
FORCEADD TAP..1
(-3725 4350);
FORCEPROP 3 LASTPIN (-3775 4350) SIG_NAME M_C_CPU0_SA_DQS_DP<3>
J 0
(-3765 4360);
DISPLAY 0.659574 (-3765 4360);
PAINT MONO (-3765 4360);
DISPLAY INVISIBLE (-3765 4360);
FORCEPROP 1 LASTPIN (-3775 4350) BN 3
J 0
(-3787 4358);
DISPLAY 0.489362 (-3787 4358);
PAINT GREEN (-3787 4358);
FORCEPROP 2 LAST CDS_LIB mstr_standard
J 0
(-3725 4350);
DISPLAY 0.723404 (-3725 4350);
PAINT MONO (-3725 4350);
DISPLAY INVISIBLE (-3725 4350);
FORCEPROP 1 LAST BODY_TYPE PLUMBING
J 0
(-3725 4400);
DISPLAY 0.872340 (-3725 4400);
PAINT GREEN (-3725 4400);
DISPLAY INVISIBLE (-3725 4400);
FORCEPROP 1 LAST HDL_TAP TRUE
J 0
(-3400 4225);
DISPLAY 0.872340 (-3400 4225);
DISPLAY INVISIBLE (-3400 4225);
FORCEPROP 1 LAST PATH I397
J 0
(-3727 4350);
DISPLAY 0.872340 (-3727 4350);
PAINT GREEN (-3727 4350);
DISPLAY INVISIBLE (-3727 4350);
FORCEADD TAP..1
(-3725 4250);
FORCEPROP 3 LASTPIN (-3775 4250) SIG_NAME M_C_CPU0_SA_DQS_DP<2>
J 0
(-3765 4260);
DISPLAY 0.659574 (-3765 4260);
PAINT MONO (-3765 4260);
DISPLAY INVISIBLE (-3765 4260);
FORCEPROP 1 LASTPIN (-3775 4250) BN 2
J 0
(-3787 4258);
DISPLAY 0.489362 (-3787 4258);
PAINT GREEN (-3787 4258);
FORCEPROP 2 LAST CDS_LIB mstr_standard
J 0
(-3725 4250);
DISPLAY 0.723404 (-3725 4250);
PAINT MONO (-3725 4250);
DISPLAY INVISIBLE (-3725 4250);
FORCEPROP 1 LAST BODY_TYPE PLUMBING
J 0
(-3725 4300);
DISPLAY 0.872340 (-3725 4300);
PAINT GREEN (-3725 4300);
DISPLAY INVISIBLE (-3725 4300);
FORCEPROP 1 LAST HDL_TAP TRUE
J 0
(-3400 4125);
DISPLAY 0.872340 (-3400 4125);
DISPLAY INVISIBLE (-3400 4125);
FORCEPROP 1 LAST PATH I398
J 0
(-3727 4250);
DISPLAY 0.872340 (-3727 4250);
PAINT GREEN (-3727 4250);
DISPLAY INVISIBLE (-3727 4250);
FORCEADD TAP..1
(-3725 4050);
FORCEPROP 3 LASTPIN (-3775 4050) SIG_NAME M_C_CPU0_SA_DQS_DP<0>
J 0
(-3765 4060);
DISPLAY 0.659574 (-3765 4060);
PAINT MONO (-3765 4060);
DISPLAY INVISIBLE (-3765 4060);
FORCEPROP 1 LASTPIN (-3775 4050) BN 0
J 0
(-3787 4058);
DISPLAY 0.489362 (-3787 4058);
PAINT GREEN (-3787 4058);
FORCEPROP 2 LAST CDS_LIB mstr_standard
J 0
(-3725 4050);
DISPLAY 0.723404 (-3725 4050);
PAINT MONO (-3725 4050);
DISPLAY INVISIBLE (-3725 4050);
FORCEPROP 1 LAST BODY_TYPE PLUMBING
J 0
(-3725 4100);
DISPLAY 0.872340 (-3725 4100);
PAINT GREEN (-3725 4100);
DISPLAY INVISIBLE (-3725 4100);
FORCEPROP 1 LAST HDL_TAP TRUE
J 0
(-3400 3925);
DISPLAY 0.872340 (-3400 3925);
DISPLAY INVISIBLE (-3400 3925);
FORCEPROP 1 LAST PATH I399
J 0
(-3727 4050);
DISPLAY 0.872340 (-3727 4050);
PAINT GREEN (-3727 4050);
DISPLAY INVISIBLE (-3727 4050);
FORCEADD TAP..1
(-3725 4150);
FORCEPROP 3 LASTPIN (-3775 4150) SIG_NAME M_C_CPU0_SA_DQS_DP<1>
J 0
(-3765 4160);
DISPLAY 0.659574 (-3765 4160);
PAINT MONO (-3765 4160);
DISPLAY INVISIBLE (-3765 4160);
FORCEPROP 1 LASTPIN (-3775 4150) BN 1
J 0
(-3787 4158);
DISPLAY 0.489362 (-3787 4158);
PAINT GREEN (-3787 4158);
FORCEPROP 2 LAST CDS_LIB mstr_standard
J 0
(-3725 4150);
DISPLAY 0.723404 (-3725 4150);
PAINT MONO (-3725 4150);
DISPLAY INVISIBLE (-3725 4150);
FORCEPROP 1 LAST BODY_TYPE PLUMBING
J 0
(-3725 4200);
DISPLAY 0.872340 (-3725 4200);
PAINT GREEN (-3725 4200);
DISPLAY INVISIBLE (-3725 4200);
FORCEPROP 1 LAST HDL_TAP TRUE
J 0
(-3400 4025);
DISPLAY 0.872340 (-3400 4025);
DISPLAY INVISIBLE (-3400 4025);
FORCEPROP 1 LAST PATH I400
J 0
(-3727 4150);
DISPLAY 0.872340 (-3727 4150);
PAINT GREEN (-3727 4150);
DISPLAY INVISIBLE (-3727 4150);
FORCEADD TAP..1
(-3725 3800);
FORCEPROP 3 LASTPIN (-3775 3800) SIG_NAME M_C_CPU0_SB_DQS_DP<8>
J 0
(-3765 3810);
DISPLAY 0.659574 (-3765 3810);
PAINT MONO (-3765 3810);
DISPLAY INVISIBLE (-3765 3810);
FORCEPROP 1 LASTPIN (-3775 3800) BN 8
J 0
(-3787 3808);
DISPLAY 0.489362 (-3787 3808);
PAINT GREEN (-3787 3808);
FORCEPROP 2 LAST CDS_LIB mstr_standard
J 0
(-3725 3800);
DISPLAY 0.723404 (-3725 3800);
PAINT MONO (-3725 3800);
DISPLAY INVISIBLE (-3725 3800);
FORCEPROP 1 LAST BODY_TYPE PLUMBING
J 0
(-3725 3850);
DISPLAY 0.872340 (-3725 3850);
PAINT GREEN (-3725 3850);
DISPLAY INVISIBLE (-3725 3850);
FORCEPROP 1 LAST HDL_TAP TRUE
J 0
(-3400 3675);
DISPLAY 0.872340 (-3400 3675);
DISPLAY INVISIBLE (-3400 3675);
FORCEPROP 1 LAST PATH I401
J 0
(-3727 3800);
DISPLAY 0.872340 (-3727 3800);
PAINT GREEN (-3727 3800);
DISPLAY INVISIBLE (-3727 3800);
FORCEADD TAP..1
(-3725 3900);
FORCEPROP 3 LASTPIN (-3775 3900) SIG_NAME M_C_CPU0_SB_DQS_DP<9>
J 0
(-3765 3910);
DISPLAY 0.659574 (-3765 3910);
PAINT MONO (-3765 3910);
DISPLAY INVISIBLE (-3765 3910);
FORCEPROP 1 LASTPIN (-3775 3900) BN 9
J 0
(-3787 3908);
DISPLAY 0.489362 (-3787 3908);
PAINT GREEN (-3787 3908);
FORCEPROP 2 LAST CDS_LIB mstr_standard
J 0
(-3725 3900);
DISPLAY 0.723404 (-3725 3900);
PAINT MONO (-3725 3900);
DISPLAY INVISIBLE (-3725 3900);
FORCEPROP 1 LAST BODY_TYPE PLUMBING
J 0
(-3725 3950);
DISPLAY 0.872340 (-3725 3950);
PAINT GREEN (-3725 3950);
DISPLAY INVISIBLE (-3725 3950);
FORCEPROP 1 LAST HDL_TAP TRUE
J 0
(-3400 3775);
DISPLAY 0.872340 (-3400 3775);
DISPLAY INVISIBLE (-3400 3775);
FORCEPROP 1 LAST PATH I402
J 0
(-3727 3900);
DISPLAY 0.872340 (-3727 3900);
PAINT GREEN (-3727 3900);
DISPLAY INVISIBLE (-3727 3900);
FORCEADD TAP..1
(-3725 3700);
FORCEPROP 3 LASTPIN (-3775 3700) SIG_NAME M_C_CPU0_SB_DQS_DP<7>
J 0
(-3765 3710);
DISPLAY 0.659574 (-3765 3710);
PAINT MONO (-3765 3710);
DISPLAY INVISIBLE (-3765 3710);
FORCEPROP 1 LASTPIN (-3775 3700) BN 7
J 0
(-3787 3708);
DISPLAY 0.489362 (-3787 3708);
PAINT GREEN (-3787 3708);
FORCEPROP 2 LAST CDS_LIB mstr_standard
J 0
(-3725 3700);
DISPLAY 0.723404 (-3725 3700);
PAINT MONO (-3725 3700);
DISPLAY INVISIBLE (-3725 3700);
FORCEPROP 1 LAST BODY_TYPE PLUMBING
J 0
(-3725 3750);
DISPLAY 0.872340 (-3725 3750);
PAINT GREEN (-3725 3750);
DISPLAY INVISIBLE (-3725 3750);
FORCEPROP 1 LAST HDL_TAP TRUE
J 0
(-3400 3575);
DISPLAY 0.872340 (-3400 3575);
DISPLAY INVISIBLE (-3400 3575);
FORCEPROP 1 LAST PATH I403
J 0
(-3727 3700);
DISPLAY 0.872340 (-3727 3700);
PAINT GREEN (-3727 3700);
DISPLAY INVISIBLE (-3727 3700);
FORCEADD TAP..1
(-3725 3600);
FORCEPROP 3 LASTPIN (-3775 3600) SIG_NAME M_C_CPU0_SB_DQS_DP<6>
J 0
(-3765 3610);
DISPLAY 0.659574 (-3765 3610);
PAINT MONO (-3765 3610);
DISPLAY INVISIBLE (-3765 3610);
FORCEPROP 1 LASTPIN (-3775 3600) BN 6
J 0
(-3787 3608);
DISPLAY 0.489362 (-3787 3608);
PAINT GREEN (-3787 3608);
FORCEPROP 2 LAST CDS_LIB mstr_standard
J 0
(-3725 3600);
DISPLAY 0.723404 (-3725 3600);
PAINT MONO (-3725 3600);
DISPLAY INVISIBLE (-3725 3600);
FORCEPROP 1 LAST BODY_TYPE PLUMBING
J 0
(-3725 3650);
DISPLAY 0.872340 (-3725 3650);
PAINT GREEN (-3725 3650);
DISPLAY INVISIBLE (-3725 3650);
FORCEPROP 1 LAST HDL_TAP TRUE
J 0
(-3400 3475);
DISPLAY 0.872340 (-3400 3475);
DISPLAY INVISIBLE (-3400 3475);
FORCEPROP 1 LAST PATH I404
J 0
(-3727 3600);
DISPLAY 0.872340 (-3727 3600);
PAINT GREEN (-3727 3600);
DISPLAY INVISIBLE (-3727 3600);
FORCEADD TAP..1
(-3725 3500);
FORCEPROP 3 LASTPIN (-3775 3500) SIG_NAME M_C_CPU0_SB_DQS_DP<5>
J 0
(-3765 3510);
DISPLAY 0.659574 (-3765 3510);
PAINT MONO (-3765 3510);
DISPLAY INVISIBLE (-3765 3510);
FORCEPROP 1 LASTPIN (-3775 3500) BN 5
J 0
(-3787 3508);
DISPLAY 0.489362 (-3787 3508);
PAINT GREEN (-3787 3508);
FORCEPROP 2 LAST CDS_LIB mstr_standard
J 0
(-3725 3500);
DISPLAY 0.723404 (-3725 3500);
PAINT MONO (-3725 3500);
DISPLAY INVISIBLE (-3725 3500);
FORCEPROP 1 LAST BODY_TYPE PLUMBING
J 0
(-3725 3550);
DISPLAY 0.872340 (-3725 3550);
PAINT GREEN (-3725 3550);
DISPLAY INVISIBLE (-3725 3550);
FORCEPROP 1 LAST HDL_TAP TRUE
J 0
(-3400 3375);
DISPLAY 0.872340 (-3400 3375);
DISPLAY INVISIBLE (-3400 3375);
FORCEPROP 1 LAST PATH I405
J 0
(-3727 3500);
DISPLAY 0.872340 (-3727 3500);
PAINT GREEN (-3727 3500);
DISPLAY INVISIBLE (-3727 3500);
FORCEADD TAP..1
(-3725 3400);
FORCEPROP 3 LASTPIN (-3775 3400) SIG_NAME M_C_CPU0_SB_DQS_DP<4>
J 0
(-3765 3410);
DISPLAY 0.659574 (-3765 3410);
PAINT MONO (-3765 3410);
DISPLAY INVISIBLE (-3765 3410);
FORCEPROP 1 LASTPIN (-3775 3400) BN 4
J 0
(-3787 3408);
DISPLAY 0.489362 (-3787 3408);
PAINT GREEN (-3787 3408);
FORCEPROP 2 LAST CDS_LIB mstr_standard
J 0
(-3725 3400);
DISPLAY 0.723404 (-3725 3400);
PAINT MONO (-3725 3400);
DISPLAY INVISIBLE (-3725 3400);
FORCEPROP 1 LAST BODY_TYPE PLUMBING
J 0
(-3725 3450);
DISPLAY 0.872340 (-3725 3450);
PAINT GREEN (-3725 3450);
DISPLAY INVISIBLE (-3725 3450);
FORCEPROP 1 LAST HDL_TAP TRUE
J 0
(-3400 3275);
DISPLAY 0.872340 (-3400 3275);
DISPLAY INVISIBLE (-3400 3275);
FORCEPROP 1 LAST PATH I406
J 0
(-3727 3400);
DISPLAY 0.872340 (-3727 3400);
PAINT GREEN (-3727 3400);
DISPLAY INVISIBLE (-3727 3400);
FORCEADD TAP..1
(-3725 3300);
FORCEPROP 3 LASTPIN (-3775 3300) SIG_NAME M_C_CPU0_SB_DQS_DP<3>
J 0
(-3765 3310);
DISPLAY 0.659574 (-3765 3310);
PAINT MONO (-3765 3310);
DISPLAY INVISIBLE (-3765 3310);
FORCEPROP 1 LASTPIN (-3775 3300) BN 3
J 0
(-3787 3308);
DISPLAY 0.489362 (-3787 3308);
PAINT GREEN (-3787 3308);
FORCEPROP 2 LAST CDS_LIB mstr_standard
J 0
(-3725 3300);
DISPLAY 0.723404 (-3725 3300);
PAINT MONO (-3725 3300);
DISPLAY INVISIBLE (-3725 3300);
FORCEPROP 1 LAST BODY_TYPE PLUMBING
J 0
(-3725 3350);
DISPLAY 0.872340 (-3725 3350);
PAINT GREEN (-3725 3350);
DISPLAY INVISIBLE (-3725 3350);
FORCEPROP 1 LAST HDL_TAP TRUE
J 0
(-3400 3175);
DISPLAY 0.872340 (-3400 3175);
DISPLAY INVISIBLE (-3400 3175);
FORCEPROP 1 LAST PATH I407
J 0
(-3727 3300);
DISPLAY 0.872340 (-3727 3300);
PAINT GREEN (-3727 3300);
DISPLAY INVISIBLE (-3727 3300);
FORCEADD TAP..1
(-3725 3200);
FORCEPROP 3 LASTPIN (-3775 3200) SIG_NAME M_C_CPU0_SB_DQS_DP<2>
J 0
(-3765 3210);
DISPLAY 0.659574 (-3765 3210);
PAINT MONO (-3765 3210);
DISPLAY INVISIBLE (-3765 3210);
FORCEPROP 1 LASTPIN (-3775 3200) BN 2
J 0
(-3787 3208);
DISPLAY 0.489362 (-3787 3208);
PAINT GREEN (-3787 3208);
FORCEPROP 2 LAST CDS_LIB mstr_standard
J 0
(-3725 3200);
DISPLAY 0.723404 (-3725 3200);
PAINT MONO (-3725 3200);
DISPLAY INVISIBLE (-3725 3200);
FORCEPROP 1 LAST BODY_TYPE PLUMBING
J 0
(-3725 3250);
DISPLAY 0.872340 (-3725 3250);
PAINT GREEN (-3725 3250);
DISPLAY INVISIBLE (-3725 3250);
FORCEPROP 1 LAST HDL_TAP TRUE
J 0
(-3400 3075);
DISPLAY 0.872340 (-3400 3075);
DISPLAY INVISIBLE (-3400 3075);
FORCEPROP 1 LAST PATH I408
J 0
(-3727 3200);
DISPLAY 0.872340 (-3727 3200);
PAINT GREEN (-3727 3200);
DISPLAY INVISIBLE (-3727 3200);
FORCEADD TAP..1
(-3725 3100);
FORCEPROP 3 LASTPIN (-3775 3100) SIG_NAME M_C_CPU0_SB_DQS_DP<1>
J 0
(-3765 3110);
DISPLAY 0.659574 (-3765 3110);
PAINT MONO (-3765 3110);
DISPLAY INVISIBLE (-3765 3110);
FORCEPROP 1 LASTPIN (-3775 3100) BN 1
J 0
(-3787 3108);
DISPLAY 0.489362 (-3787 3108);
PAINT GREEN (-3787 3108);
FORCEPROP 2 LAST CDS_LIB mstr_standard
J 0
(-3725 3100);
DISPLAY 0.723404 (-3725 3100);
PAINT MONO (-3725 3100);
DISPLAY INVISIBLE (-3725 3100);
FORCEPROP 1 LAST BODY_TYPE PLUMBING
J 0
(-3725 3150);
DISPLAY 0.872340 (-3725 3150);
PAINT GREEN (-3725 3150);
DISPLAY INVISIBLE (-3725 3150);
FORCEPROP 1 LAST HDL_TAP TRUE
J 0
(-3400 2975);
DISPLAY 0.872340 (-3400 2975);
DISPLAY INVISIBLE (-3400 2975);
FORCEPROP 1 LAST PATH I409
J 0
(-3727 3100);
DISPLAY 0.872340 (-3727 3100);
PAINT GREEN (-3727 3100);
DISPLAY INVISIBLE (-3727 3100);
FORCEADD TAP..1
(-3725 3000);
FORCEPROP 3 LASTPIN (-3775 3000) SIG_NAME M_C_CPU0_SB_DQS_DP<0>
J 0
(-3765 3010);
DISPLAY 0.659574 (-3765 3010);
PAINT MONO (-3765 3010);
DISPLAY INVISIBLE (-3765 3010);
FORCEPROP 1 LASTPIN (-3775 3000) BN 0
J 0
(-3787 3008);
DISPLAY 0.489362 (-3787 3008);
PAINT GREEN (-3787 3008);
FORCEPROP 2 LAST CDS_LIB mstr_standard
J 0
(-3725 3000);
DISPLAY 0.723404 (-3725 3000);
PAINT MONO (-3725 3000);
DISPLAY INVISIBLE (-3725 3000);
FORCEPROP 1 LAST BODY_TYPE PLUMBING
J 0
(-3725 3050);
DISPLAY 0.872340 (-3725 3050);
PAINT GREEN (-3725 3050);
DISPLAY INVISIBLE (-3725 3050);
FORCEPROP 1 LAST HDL_TAP TRUE
J 0
(-3400 2875);
DISPLAY 0.872340 (-3400 2875);
DISPLAY INVISIBLE (-3400 2875);
FORCEPROP 1 LAST PATH I410
J 0
(-3727 3000);
DISPLAY 0.872340 (-3727 3000);
PAINT GREEN (-3727 3000);
DISPLAY INVISIBLE (-3727 3000);
FORCEADD SCONN288_DDR506112002KQ..2
(-4675 3950);
FORCEPROP 1 LAST LOCATION J17
J 0
(-5275 5275);
DISPLAY 0.468085 (-5275 5275);
PAINT SKYBLUE (-5275 5275);
FORCEPROP 0 LAST $SEC 2
J 0
(-5125 5425);
DISPLAY 0.680851 (-5125 5425);
PAINT MONO (-5125 5425);
DISPLAY INVISIBLE (-5125 5425);
FORCEPROP 0 LAST CDS_SEC 2
J 0
(-5125 5425);
DISPLAY 1.021277 (-5125 5425);
DISPLAY INVISIBLE (-5125 5425);
FORCEPROP 0 LASTPIN (-3925 4000) $PN 12
J 0
(-3915 4010);
DISPLAY 0.680851 (-3915 4010);
PAINT MONO (-3915 4010);
FORCEPROP 0 LASTPIN (-3925 4050) $PN 11
J 0
(-3915 4060);
DISPLAY 0.680851 (-3915 4060);
PAINT MONO (-3915 4060);
FORCEPROP 0 LASTPIN (-3925 2950) $PN 105
J 0
(-3915 2960);
DISPLAY 0.680851 (-3915 2960);
PAINT MONO (-3915 2960);
FORCEPROP 0 LASTPIN (-3925 3000) $PN 104
J 0
(-3915 3010);
DISPLAY 0.680851 (-3915 3010);
PAINT MONO (-3915 3010);
FORCEPROP 0 LASTPIN (-3925 4100) $PN 23
J 0
(-3915 4110);
DISPLAY 0.680851 (-3915 4110);
PAINT MONO (-3915 4110);
FORCEPROP 0 LASTPIN (-3925 4150) $PN 22
J 0
(-3915 4160);
DISPLAY 0.680851 (-3915 4160);
PAINT MONO (-3915 4160);
FORCEPROP 0 LASTPIN (-3925 3050) $PN 116
J 0
(-3915 3060);
DISPLAY 0.680851 (-3915 3060);
PAINT MONO (-3915 3060);
FORCEPROP 0 LASTPIN (-3925 3100) $PN 115
J 0
(-3915 3110);
DISPLAY 0.680851 (-3915 3110);
PAINT MONO (-3915 3110);
FORCEPROP 0 LASTPIN (-3925 4200) $PN 34
J 0
(-3915 4210);
DISPLAY 0.680851 (-3915 4210);
PAINT MONO (-3915 4210);
FORCEPROP 0 LASTPIN (-3925 4250) $PN 33
J 0
(-3915 4260);
DISPLAY 0.680851 (-3915 4260);
PAINT MONO (-3915 4260);
FORCEPROP 0 LASTPIN (-3925 3150) $PN 127
J 0
(-3915 3160);
DISPLAY 0.680851 (-3915 3160);
PAINT MONO (-3915 3160);
FORCEPROP 0 LASTPIN (-3925 3200) $PN 126
J 0
(-3915 3210);
DISPLAY 0.680851 (-3915 3210);
PAINT MONO (-3915 3210);
FORCEPROP 0 LASTPIN (-3925 4300) $PN 45
J 0
(-3915 4310);
DISPLAY 0.680851 (-3915 4310);
PAINT MONO (-3915 4310);
FORCEPROP 0 LASTPIN (-3925 4350) $PN 44
J 0
(-3915 4360);
DISPLAY 0.680851 (-3915 4360);
PAINT MONO (-3915 4360);
FORCEPROP 0 LASTPIN (-3925 3250) $PN 138
J 0
(-3915 3260);
DISPLAY 0.680851 (-3915 3260);
PAINT MONO (-3915 3260);
FORCEPROP 0 LASTPIN (-3925 3300) $PN 137
J 0
(-3915 3310);
DISPLAY 0.680851 (-3915 3310);
PAINT MONO (-3915 3310);
FORCEPROP 0 LASTPIN (-3925 4400) $PN 56
J 0
(-3915 4410);
DISPLAY 0.680851 (-3915 4410);
PAINT MONO (-3915 4410);
FORCEPROP 0 LASTPIN (-3925 4450) $PN 55
J 0
(-3915 4460);
DISPLAY 0.680851 (-3915 4460);
PAINT MONO (-3915 4460);
FORCEPROP 0 LASTPIN (-3925 3350) $PN 238
J 0
(-3915 3360);
DISPLAY 0.680851 (-3915 3360);
PAINT MONO (-3915 3360);
FORCEPROP 0 LASTPIN (-3925 3400) $PN 239
J 0
(-3915 3410);
DISPLAY 0.680851 (-3915 3410);
PAINT MONO (-3915 3410);
FORCEPROP 0 LASTPIN (-3925 4500) $PN 156
J 0
(-3915 4510);
DISPLAY 0.680851 (-3915 4510);
PAINT MONO (-3915 4510);
FORCEPROP 0 LASTPIN (-3925 4550) $PN 157
J 0
(-3915 4560);
DISPLAY 0.680851 (-3915 4560);
PAINT MONO (-3915 4560);
FORCEPROP 0 LASTPIN (-3925 3450) $PN 249
J 0
(-3915 3460);
DISPLAY 0.680851 (-3915 3460);
PAINT MONO (-3915 3460);
FORCEPROP 0 LASTPIN (-3925 3500) $PN 250
J 0
(-3915 3510);
DISPLAY 0.680851 (-3915 3510);
PAINT MONO (-3915 3510);
FORCEPROP 0 LASTPIN (-3925 4600) $PN 167
J 0
(-3915 4610);
DISPLAY 0.680851 (-3915 4610);
PAINT MONO (-3915 4610);
FORCEPROP 0 LASTPIN (-3925 4650) $PN 168
J 0
(-3915 4660);
DISPLAY 0.680851 (-3915 4660);
PAINT MONO (-3915 4660);
FORCEPROP 0 LASTPIN (-3925 3550) $PN 260
J 0
(-3915 3560);
DISPLAY 0.680851 (-3915 3560);
PAINT MONO (-3915 3560);
FORCEPROP 0 LASTPIN (-3925 3600) $PN 261
J 0
(-3915 3610);
DISPLAY 0.680851 (-3915 3610);
PAINT MONO (-3915 3610);
FORCEPROP 0 LASTPIN (-3925 4700) $PN 178
J 0
(-3915 4710);
DISPLAY 0.680851 (-3915 4710);
PAINT MONO (-3915 4710);
FORCEPROP 0 LASTPIN (-3925 4750) $PN 179
J 0
(-3915 4760);
DISPLAY 0.680851 (-3915 4760);
PAINT MONO (-3915 4760);
FORCEPROP 0 LASTPIN (-3925 3650) $PN 271
J 0
(-3915 3660);
DISPLAY 0.680851 (-3915 3660);
PAINT MONO (-3915 3660);
FORCEPROP 0 LASTPIN (-3925 3700) $PN 272
J 0
(-3915 3710);
DISPLAY 0.680851 (-3915 3710);
PAINT MONO (-3915 3710);
FORCEPROP 0 LASTPIN (-3925 4800) $PN 189
J 0
(-3915 4810);
DISPLAY 0.680851 (-3915 4810);
PAINT MONO (-3915 4810);
FORCEPROP 0 LASTPIN (-3925 4850) $PN 190
J 0
(-3915 4860);
DISPLAY 0.680851 (-3915 4860);
PAINT MONO (-3915 4860);
FORCEPROP 0 LASTPIN (-3925 3750) $PN 282
J 0
(-3915 3760);
DISPLAY 0.680851 (-3915 3760);
PAINT MONO (-3915 3760);
FORCEPROP 0 LASTPIN (-3925 3800) $PN 283
J 0
(-3915 3810);
DISPLAY 0.680851 (-3915 3810);
PAINT MONO (-3915 3810);
FORCEPROP 0 LASTPIN (-3925 4900) $PN 200
J 0
(-3915 4910);
DISPLAY 0.680851 (-3915 4910);
PAINT MONO (-3915 4910);
FORCEPROP 0 LASTPIN (-3925 4950) $PN 201
J 0
(-3915 4960);
DISPLAY 0.680851 (-3915 4960);
PAINT MONO (-3915 4960);
FORCEPROP 0 LASTPIN (-3925 3850) $PN 94
J 0
(-3915 3860);
DISPLAY 0.680851 (-3915 3860);
PAINT MONO (-3915 3860);
FORCEPROP 0 LASTPIN (-3925 3900) $PN 93
J 0
(-3915 3910);
DISPLAY 0.680851 (-3915 3910);
PAINT MONO (-3915 3910);
FORCEPROP 1 LAST MATERIAL IO
J 0
(-5275 5125);
DISPLAY 0.468085 (-5275 5125);
PAINT SKYBLUE (-5275 5125);
FORCEPROP 2 LAST PART_TYPE SMLF
J 0
(-5125 5375);
DISPLAY 1.021277 (-5125 5375);
FORCEPROP 2 LAST VALUE SCONN288_DDR506112002KQ
J 0
(-5125 5325);
DISPLAY 0.489362 (-5125 5325);
PAINT SKYBLUE (-5125 5325);
FORCEPROP 1 LAST CDS_LMAN_SYM_OUTLINE -600,1150,600,-1150
J 0
(-4675 3950);
DISPLAY 0.468085 (-4675 3950);
PAINT GREEN (-4675 3950);
DISPLAY INVISIBLE (-4675 3950);
FORCEPROP 1 LAST NEEDS_NO_SIZE TRUE
J 0
(-4675 3950);
DISPLAY 0.723404 (-4675 3950);
PAINT GREEN (-4675 3950);
DISPLAY INVISIBLE (-4675 3950);
FORCEPROP 2 LAST CDS_LIB pure_quanta
J 0
(-4675 3950);
DISPLAY INVISIBLE (-4675 3950);
FORCEPROP 1 LAST PATH I411
J 0
(-4675 3950);
DISPLAY 0.723404 (-4675 3950);
PAINT GREEN (-4675 3950);
DISPLAY INVISIBLE (-4675 3950);
FORCEPROP 1 LAST PART_NUMBER DFHST8FS479
J 0
(-5275 5200);
DISPLAY 0.468085 (-5275 5200);
PAINT SKYBLUE (-5275 5200);
DISPLAY INVISIBLE (-5275 5200);
FORCEADD GND..1
(-3000 5800);
FORCEPROP 3 LASTPIN (-3000 5850) SIG_NAME GND\g
J 0
(-2990 5860);
DISPLAY 0.659574 (-2990 5860);
PAINT MONO (-2990 5860);
DISPLAY INVISIBLE (-2990 5860);
FORCEPROP 2 LAST CDS_LIB pure_quanta_power
J 0
(-3000 5800);
DISPLAY INVISIBLE (-3000 5800);
FORCEPROP 2 LAST BOM_COST MEM
J 0
(-2975 5925);
DISPLAY 0.659574 (-2975 5925);
DISPLAY INVISIBLE (-2975 5925);
FORCEPROP 1 LAST SIZE 1B
J 0
(-2925 5750);
DISPLAY 0.723404 (-2925 5750);
PAINT GREEN (-2925 5750);
DISPLAY INVISIBLE (-2925 5750);
FORCEPROP 2 LAST ROOM MEM_EFGH_DECOUPLING_CAPS
J 0
(-2975 5875);
DISPLAY 0.659574 (-2975 5875);
PAINT RED (-2975 5875);
DISPLAY INVISIBLE (-2975 5875);
FORCEPROP 1 LAST HDL_POWER GND
J 0
(-3000 5950);
DISPLAY 0.723404 (-3000 5950);
PAINT GREEN (-3000 5950);
DISPLAY INVISIBLE (-3000 5950);
FORCEPROP 1 LAST PATH I412
J 0
(-2925 5800);
DISPLAY 0.872340 (-2925 5800);
PAINT AQUA (-2925 5800);
DISPLAY INVISIBLE (-2925 5800);
FORCEADD Q_CAP..1
R 2
(-3000 6150);
FORCEPROP 1 LAST LOCATION C146
J 2
(-3050 6250);
DISPLAY 0.489362 (-3050 6250);
PAINT SKYBLUE (-3050 6250);
FORCEPROP 0 LAST $SEC 1
J 0
(-3050 6300);
DISPLAY 0.680851 (-3050 6300);
PAINT MONO (-3050 6300);
DISPLAY INVISIBLE (-3050 6300);
FORCEPROP 0 LAST CDS_SEC 1
J 0
(-3050 6300);
DISPLAY 0.680851 (-3050 6300);
DISPLAY INVISIBLE (-3050 6300);
FORCEPROP 1 LASTPIN (-3000 6250) $PN 1
J 2
(-3010 6230);
DISPLAY 0.489362 (-3010 6230);
PAINT MONO (-3010 6230);
FORCEPROP 1 LASTPIN (-3000 6050) $PN 2
J 2
(-3010 6030);
DISPLAY 0.489362 (-3010 6030);
PAINT MONO (-3010 6030);
FORCEPROP 1 LAST VOLTAGE 25V
J 2
(-3050 6150);
DISPLAY 0.489362 (-3050 6150);
PAINT SKYBLUE (-3050 6150);
FORCEPROP 1 LAST PACK_TYPE C0805
J 2
(-3050 5950);
DISPLAY 0.489362 (-3050 5950);
PAINT SKYBLUE (-3050 5950);
FORCEPROP 1 LAST VALUE 10UF
J 2
(-3050 6200);
DISPLAY 0.489362 (-3050 6200);
PAINT SKYBLUE (-3050 6200);
FORCEPROP 1 LAST TOLERANCE 10%
J 2
(-3050 6100);
DISPLAY 0.489362 (-3050 6100);
PAINT SKYBLUE (-3050 6100);
FORCEPROP 1 LAST MATERIAL X6S
J 2
(-3050 6050);
DISPLAY 0.489362 (-3050 6050);
PAINT SKYBLUE (-3050 6050);
FORCEPROP 2 LAST CDS_LIB pure_quanta
J 0
(-3000 6150);
DISPLAY INVISIBLE (-3000 6150);
FORCEPROP 0 LAST BOM_COST MEM
J 2
(-3055 6295);
DISPLAY 0.595745 (-3055 6295);
PAINT MONO (-3055 6295);
DISPLAY INVISIBLE (-3055 6295);
FORCEPROP 2 LAST ROOM 
J 2
(-3055 6295);
DISPLAY 0.595745 (-3055 6295);
PAINT RED (-3055 6295);
DISPLAY INVISIBLE (-3055 6295);
FORCEPROP 1 LAST PATH I413
J 2
(-3050 6300);
DISPLAY 0.978723 (-3050 6300);
PAINT WHITE (-3050 6300);
DISPLAY INVISIBLE (-3050 6300);
FORCEPROP 1 LAST PART_NUMBER CH6104KEA00
J 2
(-3050 6000);
DISPLAY 0.489362 (-3050 6000);
PAINT SKYBLUE (-3050 6000);
DISPLAY INVISIBLE (-3050 6000);
FORCEADD Q_CAP..1
R 2
(-2425 6150);
FORCEPROP 1 LAST LOCATION C147
J 2
(-2475 6250);
DISPLAY 0.489362 (-2475 6250);
PAINT SKYBLUE (-2475 6250);
FORCEPROP 0 LAST $SEC 1
J 0
(-2475 6300);
DISPLAY 0.680851 (-2475 6300);
PAINT MONO (-2475 6300);
DISPLAY INVISIBLE (-2475 6300);
FORCEPROP 0 LAST CDS_SEC 1
J 0
(-2475 6300);
DISPLAY 0.680851 (-2475 6300);
DISPLAY INVISIBLE (-2475 6300);
FORCEPROP 1 LASTPIN (-2425 6250) $PN 1
J 2
(-2435 6230);
DISPLAY 0.489362 (-2435 6230);
PAINT MONO (-2435 6230);
FORCEPROP 1 LASTPIN (-2425 6050) $PN 2
J 2
(-2435 6030);
DISPLAY 0.489362 (-2435 6030);
PAINT MONO (-2435 6030);
FORCEPROP 1 LAST PACK_TYPE C0805
J 2
(-2475 5950);
DISPLAY 0.489362 (-2475 5950);
PAINT SKYBLUE (-2475 5950);
FORCEPROP 1 LAST VOLTAGE 25V
J 2
(-2475 6150);
DISPLAY 0.489362 (-2475 6150);
PAINT SKYBLUE (-2475 6150);
FORCEPROP 1 LAST VALUE 10UF
J 2
(-2475 6200);
DISPLAY 0.489362 (-2475 6200);
PAINT SKYBLUE (-2475 6200);
FORCEPROP 1 LAST TOLERANCE 10%
J 2
(-2475 6100);
DISPLAY 0.489362 (-2475 6100);
PAINT SKYBLUE (-2475 6100);
FORCEPROP 1 LAST MATERIAL X6S
J 2
(-2475 6050);
DISPLAY 0.489362 (-2475 6050);
PAINT SKYBLUE (-2475 6050);
FORCEPROP 2 LAST CDS_LIB pure_quanta
J 0
(-2425 6150);
DISPLAY INVISIBLE (-2425 6150);
FORCEPROP 0 LAST BOM_COST MEM
J 2
(-2480 6295);
DISPLAY 0.595745 (-2480 6295);
PAINT MONO (-2480 6295);
DISPLAY INVISIBLE (-2480 6295);
FORCEPROP 2 LAST ROOM 
J 2
(-2480 6295);
DISPLAY 0.595745 (-2480 6295);
PAINT RED (-2480 6295);
DISPLAY INVISIBLE (-2480 6295);
FORCEPROP 1 LAST PATH I414
J 2
(-2475 6300);
DISPLAY 0.978723 (-2475 6300);
PAINT WHITE (-2475 6300);
DISPLAY INVISIBLE (-2475 6300);
FORCEPROP 1 LAST PART_NUMBER CH6104KEA00
J 2
(-2475 6000);
DISPLAY 0.489362 (-2475 6000);
PAINT SKYBLUE (-2475 6000);
DISPLAY INVISIBLE (-2475 6000);
FORCEADD UNIVERSAL_POWER..1
(-3000 6475);
FORCEPROP 3 LASTPIN (-3000 6425) SIG_NAME P12V_MEM_CPU0\g
J 0
(-2990 6435);
DISPLAY 0.659574 (-2990 6435);
PAINT MONO (-2990 6435);
DISPLAY INVISIBLE (-2990 6435);
FORCEPROP 1 LAST HDL_POWER P12V_MEM_CPU0
J 1
(-3025 6525);
DISPLAY 0.489362 (-3025 6525);
PAINT GREEN (-3025 6525);
FORCEPROP 2 LAST BOM_COST VR_SYSTEM
J 0
(-3000 6575);
DISPLAY 0.617021 (-3000 6575);
PAINT PURPLE (-3000 6575);
DISPLAY INVISIBLE (-3000 6575);
FORCEPROP 2 LAST CDS_LIB pure_quanta_power
J 0
(-3000 6475);
DISPLAY INVISIBLE (-3000 6475);
FORCEPROP 1 LAST PATH I415
J 0
(-2950 6500);
DISPLAY 0.872340 (-2950 6500);
PAINT AQUA (-2950 6500);
DISPLAY INVISIBLE (-2950 6500);
FORCEADD OFFPAGE..1
(-8525 2950);
FORCEPROP 2 LAST $XR5 91 
J 0
(-9227 2950);
DISPLAY 0.638298 (-9227 2950);
PAINT MONO (-9227 2950);
FORCEPROP 2 LAST $XR4 90 
J 0
(-9137 2950);
DISPLAY 0.638298 (-9137 2950);
PAINT MONO (-9137 2950);
FORCEPROP 2 LAST $XR3 89 
J 0
(-9047 2950);
DISPLAY 0.638298 (-9047 2950);
PAINT MONO (-9047 2950);
FORCEPROP 2 LAST $XR2 87 
J 0
(-8957 2950);
DISPLAY 0.638298 (-8957 2950);
PAINT MONO (-8957 2950);
FORCEPROP 2 LAST $XR1 86 
J 0
(-8867 2950);
DISPLAY 0.638298 (-8867 2950);
PAINT MONO (-8867 2950);
FORCEPROP 2 LAST $XR0 159 
J 0
(-8777 2950);
DISPLAY 0.638298 (-8777 2950);
PAINT MONO (-8777 2950);
FORCEPROP 2 LAST CDS_LIB mstr_standard
J 0
(-8525 2950);
DISPLAY 0.808511 (-8525 2950);
DISPLAY INVISIBLE (-8525 2950);
FORCEPROP 1 LAST OFFPAGE TRUE
J 0
(-8200 2825);
DISPLAY 0.872340 (-8200 2825);
PAINT GREEN (-8200 2825);
DISPLAY INVISIBLE (-8200 2825);
FORCEPROP 1 LAST COMMENT_BODY TRUE
J 0
(-8400 2850);
DISPLAY 0.872340 (-8400 2850);
PAINT GREEN (-8400 2850);
DISPLAY INVISIBLE (-8400 2850);
FORCEPROP 2 LAST PATH I416
J 0
(-8800 3000);
DISPLAY 0.680851 (-8800 3000);
DISPLAY INVISIBLE (-8800 3000);
FORCEADD Q_RES..1
(-7950 2950);
FORCEPROP 1 LAST LOCATION R1570
J 0
(-8000 2975);
DISPLAY 0.510638 (-8000 2975);
PAINT SKYBLUE (-8000 2975);
FORCEPROP 0 LAST $SEC 1
J 0
(-8000 3050);
DISPLAY 0.680851 (-8000 3050);
PAINT MONO (-8000 3050);
DISPLAY INVISIBLE (-8000 3050);
FORCEPROP 0 LAST CDS_SEC 1
J 0
(-8000 3050);
DISPLAY 0.680851 (-8000 3050);
DISPLAY INVISIBLE (-8000 3050);
FORCEPROP 1 LASTPIN (-8050 2950) $PN 1
J 0
(-8038 2962);
DISPLAY 0.787234 (-8038 2962);
PAINT MONO (-8038 2962);
FORCEPROP 1 LASTPIN (-7850 2950) $PN 2
J 0
(-7888 2962);
DISPLAY 0.787234 (-7888 2962);
PAINT MONO (-7888 2962);
FORCEPROP 1 LAST VALUE 49.9
J 2
(-7850 3025);
DISPLAY 0.404255 (-7850 3025);
PAINT SKYBLUE (-7850 3025);
FORCEPROP 2 LAST CDS_LIB pure_quanta
J 0
(-7950 2950);
DISPLAY INVISIBLE (-7950 2950);
FORCEPROP 1 LAST MATERIAL CHIP
J 0
(-7950 2800);
DISPLAY 0.978723 (-7950 2800);
DISPLAY INVISIBLE (-7950 2800);
FORCEPROP 1 LAST PACK_TYPE 0402LF
J 0
(-7700 2800);
DISPLAY 0.978723 (-7700 2800);
DISPLAY INVISIBLE (-7700 2800);
FORCEPROP 1 LAST WATTAGE 1/16W
J 2
(-7975 2800);
DISPLAY 0.978723 (-7975 2800);
DISPLAY INVISIBLE (-7975 2800);
FORCEPROP 1 LAST TOLERANCE 1%
J 0
(-7950 2850);
DISPLAY 0.978723 (-7950 2850);
DISPLAY INVISIBLE (-7950 2850);
FORCEPROP 1 LAST PATH I417
J 0
(-8000 3100);
DISPLAY 0.978723 (-8000 3100);
PAINT WHITE (-8000 3100);
DISPLAY INVISIBLE (-8000 3100);
FORCEPROP 1 LAST PART_NUMBER CS04992FB07
J 0
(-8000 3050);
DISPLAY 0.978723 (-8000 3050);
DISPLAY INVISIBLE (-8000 3050);
FORCEADD Q_RES..1
(-8275 3175);
FORCEPROP 1 LAST LOCATION R1677
J 0
(-8450 3175);
DISPLAY 0.510638 (-8450 3175);
FORCEPROP 0 LAST $SEC 1
J 0
(-8125 3200);
DISPLAY 0.680851 (-8125 3200);
PAINT MONO (-8125 3200);
DISPLAY INVISIBLE (-8125 3200);
FORCEPROP 0 LAST CDS_SEC 1
J 0
(-8125 3200);
DISPLAY 0.680851 (-8125 3200);
DISPLAY INVISIBLE (-8125 3200);
FORCEPROP 1 LASTPIN (-8375 3175) $PN 1
J 0
(-8363 3187);
DISPLAY 0.787234 (-8363 3187);
PAINT MONO (-8363 3187);
FORCEPROP 1 LASTPIN (-8175 3175) $PN 2
J 0
(-8213 3187);
DISPLAY 0.787234 (-8213 3187);
PAINT MONO (-8213 3187);
FORCEPROP 1 LAST PACK_TYPE 0402LF
J 0
(-8225 3150);
DISPLAY 0.404255 (-8225 3150);
FORCEPROP 1 LAST MATERIAL CHIP
J 0
(-8375 3150);
DISPLAY 0.404255 (-8375 3150);
FORCEPROP 1 LAST VALUE 10
J 2
(-8125 3175);
DISPLAY 0.404255 (-8125 3175);
FORCEPROP 2 LAST CDS_LIB pure_quanta
J 0
(-8275 3175);
DISPLAY INVISIBLE (-8275 3175);
FORCEPROP 1 LAST TOLERANCE 1%
J 0
(-8275 3075);
DISPLAY 0.978723 (-8275 3075);
DISPLAY INVISIBLE (-8275 3075);
FORCEPROP 1 LAST WATTAGE 1/16W
J 2
(-8300 3025);
DISPLAY 0.978723 (-8300 3025);
DISPLAY INVISIBLE (-8300 3025);
FORCEPROP 1 LAST PATH I418
J 0
(-8325 3325);
DISPLAY 0.978723 (-8325 3325);
PAINT WHITE (-8325 3325);
DISPLAY INVISIBLE (-8325 3325);
FORCEPROP 1 LAST PART_NUMBER CS01002FB07
J 0
(-8325 3275);
DISPLAY 0.978723 (-8325 3275);
DISPLAY INVISIBLE (-8325 3275);
FORCEADD OFFPAGE..6
(-8950 3100);
FORCEPROP 2 LAST $XR5 159 
J 0
(-9439 3064);
DISPLAY 0.638298 (-9439 3064);
PAINT MONO (-9439 3064);
FORCEPROP 2 LAST $XR4 91 
J 0
(-9319 3064);
DISPLAY 0.638298 (-9319 3064);
PAINT MONO (-9319 3064);
FORCEPROP 2 LAST $XR3 90 
J 0
(-9229 3064);
DISPLAY 0.638298 (-9229 3064);
PAINT MONO (-9229 3064);
FORCEPROP 2 LAST $XR2 89 
J 0
(-9409 3100);
DISPLAY 0.638298 (-9409 3100);
PAINT MONO (-9409 3100);
FORCEPROP 2 LAST $XR1 87 
J 0
(-9319 3100);
DISPLAY 0.638298 (-9319 3100);
PAINT MONO (-9319 3100);
FORCEPROP 2 LAST $XR0 86 
J 0
(-9229 3100);
DISPLAY 0.638298 (-9229 3100);
PAINT MONO (-9229 3100);
FORCEPROP 2 LAST CDS_LIB mstr_standard
J 0
(-8950 3100);
DISPLAY 0.808511 (-8950 3100);
DISPLAY INVISIBLE (-8950 3100);
FORCEPROP 1 LAST OFFPAGE TRUE
J 0
(-8625 2975);
DISPLAY 0.872340 (-8625 2975);
PAINT GREEN (-8625 2975);
DISPLAY INVISIBLE (-8625 2975);
FORCEPROP 1 LAST COMMENT_BODY TRUE
J 0
(-8850 3025);
DISPLAY 0.872340 (-8850 3025);
PAINT GREEN (-8850 3025);
DISPLAY INVISIBLE (-8850 3025);
FORCEPROP 2 LAST PATH I419
J 0
(-9175 3150);
DISPLAY 0.680851 (-9175 3150);
DISPLAY INVISIBLE (-9175 3150);
FORCEADD DNS..2
(-8525 2625);
PAINT RED (-8525 2625);
FORCEPROP 2 LAST CDS_LIB mstr_misc
J 0
(-8525 2625);
DISPLAY INVISIBLE (-8525 2625);
FORCEPROP 1 LAST COMMENT_BODY TRUE
R 1
J 0
(-8450 2400);
DISPLAY 0.872340 (-8450 2400);
PAINT PEACH (-8450 2400);
DISPLAY INVISIBLE (-8450 2400);
FORCEADD QUANTA_TITLE_BLOCK_C..1
(-100 100);
FORCEPROP 0 LAST CDS_CON_LAST_MODIFIED Thu Sep 14 16:12:06 2023
J 0
(-1985 115);
DISPLAY INVISIBLE (-1985 115);
FORCEPROP 1 LAST CUSTOM_TXT_CDS <CON_LAST_MODIFIED>
J 0
(-1985 115);
DISPLAY 0.978723 (-1985 115);
FORCEPROP 2 LAST CUSTOM_TXT_CDS <XR_PAGE_TITLE>
J 0
(-7990 5350);
DISPLAY 0.638298 (-7990 5350);
PAINT PINK (-7990 5350);
DISPLAY INVISIBLE (-7990 5350);
FORCEPROP 1 LAST CUSTOM_TXT_CDS <NAME_2>
J 0
(-3275 150);
FORCEPROP 1 LAST CUSTOM_TXT_CDS <NAME_1>
J 0
(-3275 275);
FORCEPROP 1 LAST CUSTOM_TXT_CDS <Q_NUMBER>
J 0
(-1503 203);
DISPLAY 1.212766 (-1503 203);
FORCEPROP 1 LAST CUSTOM_TXT_CDS <Q_PROJ>
J 0
(-2482 202);
DISPLAY 1.212766 (-2482 202);
FORCEPROP 1 LAST CUSTOM_TXT_CDS <Q_REV>
J 0
(-284 203);
DISPLAY 1.212766 (-284 203);
FORCEPROP 1 LAST CUSTOM_TXT_CDS <CON_PAGE_NUM> OF <CON_TOTAL_PAGES>
J 0
(-546 118);
DISPLAY 0.978723 (-546 118);
FORCEPROP 1 LAST Q_TITLE DDR5 - CPU0 CHC
J 0
(-9425 150);
DISPLAY 2.446809 (-9425 150);
PAINT GREEN (-9425 150);
FORCEPROP 2 LAST CDS_LIB pure_quanta
J 0
(-100 100);
DISPLAY INVISIBLE (-100 100);
FORCEPROP 1 LAST CDS_LMAN_SYM_OUTLINE -9475,6775,100,-125
J 0
(-100 100);
DISPLAY 0.468085 (-100 100);
PAINT GREEN (-100 100);
DISPLAY INVISIBLE (-100 100);
FORCEPROP 2 LAST PAGE_BORDER TRUE
J 0
(-7990 5350);
DISPLAY 0.638298 (-7990 5350);
PAINT PINK (-7990 5350);
DISPLAY INVISIBLE (-7990 5350);
FORCEPROP 2 LAST CDS_XR_PAGE_TITLE CR-88 : @T6G_MB_LIB.T6G(SCH_1):PAGE88
J 0
(-7990 5350);
DISPLAY 0.638298 (-7990 5350);
PAINT PINK (-7990 5350);
DISPLAY INVISIBLE (-7990 5350);
FORCEPROP 1 LAST Q_DEPT BU9
J 1
(-3863 149);
DISPLAY 1.957447 (-3863 149);
PAINT GREEN (-3863 149);
DISPLAY INVISIBLE (-3863 149);
FORCEPROP 1 LAST COMMENT_BODY TRUE
J 0
(-88 87);
DISPLAY 0.978723 (-88 87);
PAINT GREEN (-88 87);
DISPLAY INVISIBLE (-88 87);
WIRE 17 -1 (-6175 5775)(-6175 5750);
WIRE 17 -1 (-6175 5775)(-5725 5775);
FORCEPROP 2 LAST SIG_NAME M_C_CPU0_SA_DQ<31:0>
J 2
(-5725 5785);
DISPLAY 0.489362 (-5725 5785);
WIRE 17 -1 (-7975 4350)(-7975 4375);
WIRE 17 -1 (-7975 4350)(-7975 4300);
WIRE 17 -1 (-7975 4375)(-8475 4375);
FORCEPROP 2 LAST SIG_NAME M_C_CPU0_SA_CB<7:0>
J 0
(-8475 4385);
DISPLAY 0.489362 (-8475 4385);
WIRE 17 -1 (-7975 4250)(-7975 4200);
WIRE 17 -1 (-7975 4250)(-7975 4300);
WIRE 17 -1 (-7975 4150)(-7975 4200);
WIRE 17 -1 (-7975 4100)(-7975 4150);
WIRE 17 -1 (-7975 4050)(-7975 4100);
WIRE 17 -1 (-7975 4000)(-7975 4050);
WIRE 17 -1 (-7975 3900)(-7975 3925);
WIRE 17 -1 (-7975 3900)(-7975 3850);
WIRE 17 -1 (-7975 3925)(-8475 3925);
FORCEPROP 2 LAST SIG_NAME M_C_CPU0_SB_CB<7:0>
J 0
(-8475 3935);
DISPLAY 0.489362 (-8475 3935);
WIRE 17 -1 (-7975 5450)(-7975 5500);
WIRE 17 -1 (-7975 5500)(-7975 5550);
WIRE 17 -1 (-7975 5550)(-7975 5600);
WIRE 17 -1 (-7975 5600)(-7975 5650);
WIRE 17 -1 (-7975 5650)(-7975 5700);
WIRE 17 -1 (-7975 5700)(-7975 5750);
WIRE 17 -1 (-7975 5750)(-7975 5775);
WIRE 17 -1 (-7975 5775)(-8475 5775);
FORCEPROP 2 LAST SIG_NAME M_C_CPU0_SA_CA<6:0>
J 0
(-8475 5785);
DISPLAY 0.489362 (-8475 5785);
WIRE 17 -1 (-7975 5050)(-7975 5100);
WIRE 17 -1 (-7975 5100)(-7975 5150);
WIRE 17 -1 (-7975 5150)(-7975 5200);
WIRE 17 -1 (-7975 5200)(-7975 5250);
WIRE 17 -1 (-7975 5250)(-7975 5300);
WIRE 17 -1 (-7975 5300)(-7975 5350);
WIRE 17 -1 (-7975 5350)(-7975 5375);
WIRE 17 -1 (-7975 5375)(-8475 5375);
FORCEPROP 2 LAST SIG_NAME M_C_CPU0_SB_CA<6:0>
J 0
(-8475 5385);
DISPLAY 0.489362 (-8475 5385);
WIRE 17 -1 (-7975 3800)(-7975 3850);
WIRE 17 -1 (-7975 3800)(-7975 3750);
WIRE 17 -1 (-7975 3700)(-7975 3750);
WIRE 17 -1 (-7975 3650)(-7975 3700);
WIRE 17 -1 (-7975 3600)(-7975 3650);
WIRE 17 -1 (-7975 3550)(-7975 3600);
WIRE 17 -1 (-6175 5750)(-6175 5700);
WIRE 17 -1 (-6175 5700)(-6175 5650);
WIRE 17 -1 (-6175 5650)(-6175 5600);
WIRE 17 -1 (-6175 5600)(-6175 5550);
WIRE 17 -1 (-6175 5550)(-6175 5500);
WIRE 17 -1 (-6175 5500)(-6175 5450);
WIRE 17 -1 (-6175 5450)(-6175 5400);
WIRE 17 -1 (-6175 5400)(-6175 5350);
WIRE 17 -1 (-6175 5350)(-6175 5300);
WIRE 17 -1 (-6175 5300)(-6175 5250);
WIRE 17 -1 (-6175 5250)(-6175 5200);
WIRE 17 -1 (-6175 5200)(-6175 5150);
WIRE 17 -1 (-6175 5150)(-6175 5100);
WIRE 17 -1 (-6175 5100)(-6175 5050);
WIRE 17 -1 (-6175 5050)(-6175 5000);
WIRE 17 -1 (-6175 4950)(-6175 5000);
WIRE 17 -1 (-6175 4900)(-6175 4950);
WIRE 17 -1 (-6175 4850)(-6175 4900);
WIRE 17 -1 (-6175 4800)(-6175 4850);
WIRE 17 -1 (-6175 4800)(-6175 4750);
WIRE 17 -1 (-6175 4750)(-6175 4700);
WIRE 17 -1 (-6175 4700)(-6175 4650);
WIRE 17 -1 (-6175 4650)(-6175 4600);
WIRE 17 -1 (-6175 4600)(-6175 4550);
WIRE 17 -1 (-6175 4550)(-6175 4500);
WIRE 17 -1 (-6175 4500)(-6175 4450);
WIRE 17 -1 (-6175 4450)(-6175 4400);
WIRE 17 -1 (-6175 4350)(-6175 4400);
WIRE 17 -1 (-6175 4300)(-6175 4350);
WIRE 17 -1 (-6175 4250)(-6175 4300);
WIRE 17 -1 (-6175 4200)(-6175 4250);
WIRE 17 -1 (-6175 4125)(-6175 4100);
WIRE 17 -1 (-6175 4125)(-5725 4125);
FORCEPROP 2 LAST SIG_NAME M_C_CPU0_SB_DQ<31:0>
J 2
(-5725 4135);
DISPLAY 0.489362 (-5725 4135);
WIRE 17 -1 (-6175 4100)(-6175 4050);
WIRE 17 -1 (-6175 4050)(-6175 4000);
WIRE 17 -1 (-6175 4000)(-6175 3950);
WIRE 17 -1 (-6175 3950)(-6175 3900);
WIRE 17 -1 (-6175 3900)(-6175 3850);
WIRE 17 -1 (-6175 3850)(-6175 3800);
WIRE 17 -1 (-6175 3800)(-6175 3750);
WIRE 17 -1 (-6175 3750)(-6175 3700);
WIRE 17 -1 (-6175 3700)(-6175 3650);
WIRE 17 -1 (-6175 3650)(-6175 3600);
WIRE 17 -1 (-6175 3600)(-6175 3550);
WIRE 17 -1 (-6175 3550)(-6175 3500);
WIRE 17 -1 (-6175 3500)(-6175 3450);
WIRE 17 -1 (-6175 3450)(-6175 3400);
WIRE 17 -1 (-6175 3400)(-6175 3350);
WIRE 17 -1 (-6175 3300)(-6175 3350);
WIRE 17 -1 (-6175 3250)(-6175 3300);
WIRE 17 -1 (-6175 3200)(-6175 3250);
WIRE 17 -1 (-6175 3150)(-6175 3200);
WIRE 17 -1 (-6175 3150)(-6175 3100);
WIRE 17 -1 (-6175 3100)(-6175 3050);
WIRE 17 -1 (-6175 3050)(-6175 3000);
WIRE 17 -1 (-6175 3000)(-6175 2950);
WIRE 17 -1 (-6175 2950)(-6175 2900);
WIRE 17 -1 (-6175 2900)(-6175 2850);
WIRE 17 -1 (-6175 2850)(-6175 2800);
WIRE 17 -1 (-6175 2800)(-6175 2750);
WIRE 17 -1 (-6175 2700)(-6175 2750);
WIRE 17 -1 (-6175 2650)(-6175 2700);
WIRE 17 -1 (-6175 2600)(-6175 2650);
WIRE 17 -1 (-6175 2550)(-6175 2600);
WIRE 17 -1 (-3475 4825)(-3475 4725);
WIRE 17 -1 (-3475 4925)(-3475 4825);
WIRE 17 -1 (-3475 4725)(-3475 4625);
WIRE 17 -1 (-3475 4625)(-3475 4525);
WIRE 17 -1 (-3475 4950)(-3475 4925);
WIRE 17 -1 (-3475 4950)(-2775 4950);
FORCEPROP 2 LAST SIG_NAME M_C_CPU0_SA_DQS_DN<9:0>
J 0
(-3410 4960);
DISPLAY 0.489362 (-3410 4960);
WIRE 17 -1 (-3675 4775)(-3675 4675);
WIRE 17 -1 (-3675 4875)(-3675 4775);
WIRE 17 -1 (-3675 4675)(-3675 4575);
WIRE 17 -1 (-3675 4475)(-3675 4575);
WIRE 17 -1 (-3675 4975)(-3675 4875);
WIRE 17 -1 (-3675 5000)(-3675 4975);
WIRE 17 -1 (-3675 4375)(-3675 4475);
WIRE 17 -1 (-3675 4275)(-3675 4375);
WIRE 17 -1 (-3675 5000)(-2775 5000);
FORCEPROP 2 LAST SIG_NAME M_C_CPU0_SA_DQS_DP<9:0>
J 0
(-3410 5010);
DISPLAY 0.489362 (-3410 5010);
WIRE 17 -1 (-3675 3925)(-3675 3825);
WIRE 17 -1 (-3675 3950)(-3675 3925);
WIRE 17 -1 (-3675 3825)(-3675 3725);
WIRE 17 -1 (-3675 3725)(-3675 3625);
WIRE 17 -1 (-3675 3950)(-2775 3950);
FORCEPROP 2 LAST SIG_NAME M_C_CPU0_SB_DQS_DP<9:0>
J 0
(-3410 3960);
DISPLAY 0.489362 (-3410 3960);
WIRE 17 -1 (-3475 3875)(-3475 3775);
WIRE 17 -1 (-3475 3900)(-3475 3875);
WIRE 17 -1 (-3475 3775)(-3475 3675);
WIRE 17 -1 (-3475 3675)(-3475 3575);
WIRE 17 -1 (-3475 3900)(-2775 3900);
FORCEPROP 2 LAST SIG_NAME M_C_CPU0_SB_DQS_DN<9:0>
J 0
(-3410 3910);
DISPLAY 0.489362 (-3410 3910);
WIRE 17 -1 (-3675 3625)(-3675 3525);
WIRE 17 -1 (-3475 4125)(-3475 4025);
WIRE 17 -1 (-3475 4225)(-3475 4125);
WIRE 17 -1 (-3475 4225)(-3475 4325);
WIRE 17 -1 (-3475 4325)(-3475 4425);
WIRE 17 -1 (-3475 4425)(-3475 4525);
WIRE 17 -1 (-3675 4175)(-3675 4075);
WIRE 17 -1 (-3675 4275)(-3675 4175);
WIRE 17 -1 (-3475 3075)(-3475 2975);
WIRE 17 -1 (-3475 3175)(-3475 3075);
WIRE 17 -1 (-3475 3175)(-3475 3275);
WIRE 17 -1 (-3475 3275)(-3475 3375);
WIRE 17 -1 (-3475 3375)(-3475 3475);
WIRE 17 -1 (-3475 3575)(-3475 3475);
WIRE 17 -1 (-3675 3125)(-3675 3025);
WIRE 17 -1 (-3675 3225)(-3675 3125);
WIRE 17 -1 (-3675 3225)(-3675 3325);
WIRE 17 -1 (-3675 3325)(-3675 3425);
WIRE 17 -1 (-3675 3425)(-3675 3525);
WIRE 16 -1 (-6625 1400)(-6625 1475);
WIRE 16 -1 (-8925 3350)(-8925 3425);
WIRE 16 -1 (-8550 2725)(-8550 2750);
WIRE 16 -1 (-7675 3375)(-8475 3375);
FORCEPROP 2 LAST SIG_NAME M_C_CPU0_ALERT_N
J 0
(-8475 3385);
DISPLAY 0.489362 (-8475 3385);
WIRE 16 -1 (-8400 3100)(-8400 3175);
WIRE 16 -1 (-8400 3100)(-8900 3100);
FORCEPROP 2 LAST SIG_NAME I3C_SPD_DDRAF_CPU0_SDA
J 0
(-8910 3110);
DISPLAY 0.489362 (-8910 3110);
WIRE 16 -1 (-8400 3175)(-8375 3175);
WIRE 16 -1 (-8050 2950)(-8475 2950);
FORCEPROP 2 LAST SIG_NAME I3C_SPD_DDRAF_CPU0_SCL
J 0
(-8535 2960);
DISPLAY 0.489362 (-8535 2960);
WIRE 16 -1 (-7675 3425)(-8475 3425);
FORCEPROP 2 LAST SIG_NAME M_C_CPU0_RESET_N
J 0
(-8475 3435);
DISPLAY 0.489362 (-8475 3435);
WIRE 16 -1 (-2425 6350)(-2300 6350);
WIRE 16 -1 (-2425 6350)(-2425 6250);
WIRE 16 -1 (-2425 6350)(-3000 6350);
WIRE 16 -1 (-2300 5700)(-2300 6350);
WIRE 16 -1 (-2000 5700)(-2300 5700);
WIRE 16 -1 (-2300 5650)(-2300 5700);
WIRE 16 -1 (-3000 6250)(-3000 6350);
WIRE 16 -1 (-3000 6350)(-3000 6425);
WIRE 16 -1 (-2000 5650)(-2300 5650);
WIRE 16 -1 (-2300 5600)(-2300 5650);
WIRE 16 -1 (-2000 5600)(-2300 5600);
WIRE 16 -1 (-2425 5925)(-2425 6050);
WIRE 16 -1 (-2425 5925)(-3000 5925);
WIRE 16 -1 (-3000 5925)(-3000 6050);
WIRE 16 -1 (-3000 5925)(-3000 5850);
WIRE 16 -1 (-500 2550)(-500 2450);
WIRE 16 -1 (-500 2600)(-500 2550);
WIRE 16 -1 (-500 2550)(-800 2550);
WIRE 16 -1 (-500 2450)(-500 2400);
WIRE 16 -1 (-500 2450)(-800 2450);
WIRE 16 -1 (-500 2400)(-500 2350);
WIRE 16 -1 (-500 2400)(-800 2400);
WIRE 16 -1 (-500 2650)(-500 2600);
WIRE 16 -1 (-500 2600)(-800 2600);
WIRE 16 -1 (-500 2700)(-500 2650);
WIRE 16 -1 (-500 2650)(-800 2650);
WIRE 16 -1 (-500 2350)(-500 2150);
WIRE 16 -1 (-500 2350)(-800 2350);
WIRE 16 -1 (-500 2750)(-500 2700);
WIRE 16 -1 (-500 2700)(-800 2700);
WIRE 16 -1 (-500 2800)(-500 2750);
WIRE 16 -1 (-500 2750)(-800 2750);
WIRE 16 -1 (-500 2850)(-500 2800);
WIRE 16 -1 (-500 2800)(-800 2800);
WIRE 16 -1 (-500 2900)(-500 2850);
WIRE 16 -1 (-500 2850)(-800 2850);
WIRE 16 -1 (-500 2950)(-500 2900);
WIRE 16 -1 (-500 2900)(-800 2900);
WIRE 16 -1 (-500 3000)(-500 2950);
WIRE 16 -1 (-500 2950)(-800 2950);
WIRE 16 -1 (-500 3050)(-500 3000);
WIRE 16 -1 (-500 3000)(-800 3000);
WIRE 16 -1 (-500 3100)(-500 3050);
WIRE 16 -1 (-500 3050)(-800 3050);
WIRE 16 -1 (-500 3150)(-500 3100);
WIRE 16 -1 (-500 3100)(-800 3100);
WIRE 16 -1 (-500 3200)(-500 3150);
WIRE 16 -1 (-500 3150)(-800 3150);
WIRE 16 -1 (-500 3250)(-500 3200);
WIRE 16 -1 (-500 3200)(-800 3200);
WIRE 16 -1 (-500 3300)(-500 3250);
WIRE 16 -1 (-500 3250)(-800 3250);
WIRE 16 -1 (-500 3350)(-500 3300);
WIRE 16 -1 (-500 3300)(-800 3300);
WIRE 16 -1 (-500 3400)(-500 3350);
WIRE 16 -1 (-500 3350)(-800 3350);
WIRE 16 -1 (-500 3450)(-500 3400);
WIRE 16 -1 (-500 3400)(-800 3400);
WIRE 16 -1 (-500 3500)(-500 3450);
WIRE 16 -1 (-500 3450)(-800 3450);
WIRE 16 -1 (-500 3550)(-500 3500);
WIRE 16 -1 (-500 3500)(-800 3500);
WIRE 16 -1 (-500 3600)(-500 3550);
WIRE 16 -1 (-500 3550)(-800 3550);
WIRE 16 -1 (-500 3650)(-500 3600);
WIRE 16 -1 (-500 3600)(-800 3600);
WIRE 16 -1 (-500 3700)(-500 3650);
WIRE 16 -1 (-500 3650)(-800 3650);
WIRE 16 -1 (-500 3750)(-500 3700);
WIRE 16 -1 (-500 3700)(-800 3700);
WIRE 16 -1 (-500 3800)(-500 3750);
WIRE 16 -1 (-500 3750)(-800 3750);
WIRE 16 -1 (-500 3850)(-500 3800);
WIRE 16 -1 (-500 3800)(-800 3800);
WIRE 16 -1 (-500 3900)(-500 3850);
WIRE 16 -1 (-500 3850)(-800 3850);
WIRE 16 -1 (-500 3950)(-500 3900);
WIRE 16 -1 (-500 3900)(-800 3900);
WIRE 16 -1 (-500 4000)(-500 3950);
WIRE 16 -1 (-500 3950)(-800 3950);
WIRE 16 -1 (-500 4050)(-500 4000);
WIRE 16 -1 (-500 4000)(-800 4000);
WIRE 16 -1 (-500 4100)(-500 4050);
WIRE 16 -1 (-500 4050)(-800 4050);
WIRE 16 -1 (-500 4150)(-500 4100);
WIRE 16 -1 (-500 4100)(-800 4100);
WIRE 16 -1 (-500 4200)(-500 4150);
WIRE 16 -1 (-500 4150)(-800 4150);
WIRE 16 -1 (-500 4250)(-500 4200);
WIRE 16 -1 (-500 4200)(-800 4200);
WIRE 16 -1 (-500 4300)(-500 4250);
WIRE 16 -1 (-500 4250)(-800 4250);
WIRE 16 -1 (-500 4350)(-500 4300);
WIRE 16 -1 (-500 4300)(-800 4300);
WIRE 16 -1 (-500 4400)(-500 4350);
WIRE 16 -1 (-500 4350)(-800 4350);
WIRE 16 -1 (-500 4450)(-500 4400);
WIRE 16 -1 (-500 4400)(-800 4400);
WIRE 16 -1 (-500 4500)(-500 4450);
WIRE 16 -1 (-500 4450)(-800 4450);
WIRE 16 -1 (-500 4550)(-500 4500);
WIRE 16 -1 (-500 4500)(-800 4500);
WIRE 16 -1 (-500 4600)(-500 4550);
WIRE 16 -1 (-500 4550)(-800 4550);
WIRE 16 -1 (-500 4650)(-500 4600);
WIRE 16 -1 (-500 4600)(-800 4600);
WIRE 16 -1 (-500 4700)(-500 4650);
WIRE 16 -1 (-500 4650)(-800 4650);
WIRE 16 -1 (-500 4750)(-500 4700);
WIRE 16 -1 (-500 4700)(-800 4700);
WIRE 16 -1 (-500 4800)(-500 4750);
WIRE 16 -1 (-500 4750)(-800 4750);
WIRE 16 -1 (-500 4850)(-500 4800);
WIRE 16 -1 (-500 4800)(-800 4800);
WIRE 16 -1 (-500 4900)(-500 4850);
WIRE 16 -1 (-500 4850)(-800 4850);
WIRE 16 -1 (-500 4950)(-500 4900);
WIRE 16 -1 (-500 4900)(-800 4900);
WIRE 16 -1 (-500 5000)(-500 4950);
WIRE 16 -1 (-500 4950)(-800 4950);
WIRE 16 -1 (-500 5050)(-500 5000);
WIRE 16 -1 (-500 5000)(-800 5000);
WIRE 16 -1 (-500 5100)(-500 5050);
WIRE 16 -1 (-500 5050)(-800 5050);
WIRE 16 -1 (-500 5150)(-500 5100);
WIRE 16 -1 (-500 5100)(-800 5100);
WIRE 16 -1 (-500 5200)(-500 5150);
WIRE 16 -1 (-500 5150)(-800 5150);
WIRE 16 -1 (-500 5250)(-500 5200);
WIRE 16 -1 (-500 5200)(-800 5200);
WIRE 16 -1 (-500 5300)(-500 5250);
WIRE 16 -1 (-500 5250)(-800 5250);
WIRE 16 -1 (-500 5350)(-500 5300);
WIRE 16 -1 (-500 5300)(-800 5300);
WIRE 16 -1 (-500 5400)(-500 5350);
WIRE 16 -1 (-500 5350)(-800 5350);
WIRE 16 -1 (-500 5450)(-500 5400);
WIRE 16 -1 (-500 5400)(-800 5400);
WIRE 16 -1 (-500 5500)(-500 5450);
WIRE 16 -1 (-500 5450)(-800 5450);
WIRE 16 -1 (-500 5550)(-500 5500);
WIRE 16 -1 (-500 5500)(-800 5500);
WIRE 16 -1 (-500 5600)(-500 5550);
WIRE 16 -1 (-500 5550)(-800 5550);
WIRE 16 -1 (-500 5650)(-500 5600);
WIRE 16 -1 (-500 5600)(-800 5600);
WIRE 16 -1 (-500 5700)(-500 5650);
WIRE 16 -1 (-500 5650)(-800 5650);
WIRE 16 -1 (-500 5700)(-800 5700);
WIRE 16 -1 (-2000 2500)(-2300 2500);
WIRE 16 -1 (-2300 2550)(-2300 2500);
WIRE 16 -1 (-2300 2500)(-2300 2450);
WIRE 16 -1 (-2000 2450)(-2300 2450);
WIRE 16 -1 (-2300 2450)(-2300 2350);
WIRE 16 -1 (-2000 2550)(-2300 2550);
WIRE 16 -1 (-2300 2600)(-2300 2550);
WIRE 16 -1 (-2000 2600)(-2300 2600);
WIRE 16 -1 (-2300 2650)(-2300 2600);
WIRE 16 -1 (-2000 2650)(-2300 2650);
WIRE 16 -1 (-2300 2700)(-2300 2650);
WIRE 16 -1 (-2000 2700)(-2300 2700);
WIRE 16 -1 (-2300 2750)(-2300 2700);
WIRE 16 -1 (-2000 2750)(-2300 2750);
WIRE 16 -1 (-2300 2800)(-2300 2750);
WIRE 16 -1 (-2000 2800)(-2300 2800);
WIRE 16 -1 (-2300 2850)(-2300 2800);
WIRE 16 -1 (-2000 2850)(-2300 2850);
WIRE 16 -1 (-2300 2900)(-2300 2850);
WIRE 16 -1 (-2000 2900)(-2300 2900);
WIRE 16 -1 (-2300 2950)(-2300 2900);
WIRE 16 -1 (-2000 2950)(-2300 2950);
WIRE 16 -1 (-2300 3000)(-2300 2950);
WIRE 16 -1 (-2000 3000)(-2300 3000);
WIRE 16 -1 (-2300 3050)(-2300 3000);
WIRE 16 -1 (-2000 3050)(-2300 3050);
WIRE 16 -1 (-2300 3100)(-2300 3050);
WIRE 16 -1 (-2000 3100)(-2300 3100);
WIRE 16 -1 (-2300 3150)(-2300 3100);
WIRE 16 -1 (-2000 3150)(-2300 3150);
WIRE 16 -1 (-2300 3200)(-2300 3150);
WIRE 16 -1 (-2000 3200)(-2300 3200);
WIRE 16 -1 (-2300 3250)(-2300 3200);
WIRE 16 -1 (-2000 3250)(-2300 3250);
WIRE 16 -1 (-2300 3300)(-2300 3250);
WIRE 16 -1 (-2000 3300)(-2300 3300);
WIRE 16 -1 (-2300 3350)(-2300 3300);
WIRE 16 -1 (-2000 3350)(-2300 3350);
WIRE 16 -1 (-2300 3400)(-2300 3350);
WIRE 16 -1 (-2000 3400)(-2300 3400);
WIRE 16 -1 (-2300 3450)(-2300 3400);
WIRE 16 -1 (-2000 3450)(-2300 3450);
WIRE 16 -1 (-2300 3500)(-2300 3450);
WIRE 16 -1 (-2000 3500)(-2300 3500);
WIRE 16 -1 (-2300 3550)(-2300 3500);
WIRE 16 -1 (-2000 3550)(-2300 3550);
WIRE 16 -1 (-2300 3600)(-2300 3550);
WIRE 16 -1 (-2000 3600)(-2300 3600);
WIRE 16 -1 (-2300 3650)(-2300 3600);
WIRE 16 -1 (-2000 3650)(-2300 3650);
WIRE 16 -1 (-2300 3700)(-2300 3650);
WIRE 16 -1 (-2000 3700)(-2300 3700);
WIRE 16 -1 (-2300 3750)(-2300 3700);
WIRE 16 -1 (-2000 3750)(-2300 3750);
WIRE 16 -1 (-2300 3800)(-2300 3750);
WIRE 16 -1 (-2000 3800)(-2300 3800);
WIRE 16 -1 (-2300 3850)(-2300 3800);
WIRE 16 -1 (-2000 3850)(-2300 3850);
WIRE 16 -1 (-2300 3900)(-2300 3850);
WIRE 16 -1 (-2000 3900)(-2300 3900);
WIRE 16 -1 (-2300 3950)(-2300 3900);
WIRE 16 -1 (-2000 3950)(-2300 3950);
WIRE 16 -1 (-2300 4000)(-2300 3950);
WIRE 16 -1 (-2000 4000)(-2300 4000);
WIRE 16 -1 (-2300 4050)(-2300 4000);
WIRE 16 -1 (-2300 4100)(-2300 4050);
WIRE 16 -1 (-2000 4050)(-2300 4050);
WIRE 16 -1 (-2000 4100)(-2300 4100);
WIRE 16 -1 (-2300 4150)(-2300 4100);
WIRE 16 -1 (-2000 4150)(-2300 4150);
WIRE 16 -1 (-2300 4200)(-2300 4150);
WIRE 16 -1 (-2000 4200)(-2300 4200);
WIRE 16 -1 (-2300 4250)(-2300 4200);
WIRE 16 -1 (-2000 4250)(-2300 4250);
WIRE 16 -1 (-2300 4300)(-2300 4250);
WIRE 16 -1 (-2000 4300)(-2300 4300);
WIRE 16 -1 (-2300 4350)(-2300 4300);
WIRE 16 -1 (-2000 4350)(-2300 4350);
WIRE 16 -1 (-2300 4400)(-2300 4350);
WIRE 16 -1 (-2000 4400)(-2300 4400);
WIRE 16 -1 (-2300 4450)(-2300 4400);
WIRE 16 -1 (-2000 4450)(-2300 4450);
WIRE 16 -1 (-2300 4500)(-2300 4450);
WIRE 16 -1 (-2000 4500)(-2300 4500);
WIRE 16 -1 (-2300 4550)(-2300 4500);
WIRE 16 -1 (-2000 4550)(-2300 4550);
WIRE 16 -1 (-2300 4600)(-2300 4550);
WIRE 16 -1 (-2000 4600)(-2300 4600);
WIRE 16 -1 (-2300 4650)(-2300 4600);
WIRE 16 -1 (-2000 4650)(-2300 4650);
WIRE 16 -1 (-2300 4700)(-2300 4650);
WIRE 16 -1 (-2000 4700)(-2300 4700);
WIRE 16 -1 (-2300 4750)(-2300 4700);
WIRE 16 -1 (-2000 4750)(-2300 4750);
WIRE 16 -1 (-2300 4800)(-2300 4750);
WIRE 16 -1 (-2000 4800)(-2300 4800);
WIRE 16 -1 (-2300 4850)(-2300 4800);
WIRE 16 -1 (-2000 4850)(-2300 4850);
WIRE 16 -1 (-2300 4900)(-2300 4850);
WIRE 16 -1 (-2000 4900)(-2300 4900);
WIRE 16 -1 (-2300 4950)(-2300 4900);
WIRE 16 -1 (-2000 4950)(-2300 4950);
WIRE 16 -1 (-2300 5000)(-2300 4950);
WIRE 16 -1 (-2000 5000)(-2300 5000);
WIRE 16 -1 (-2300 5050)(-2300 5000);
WIRE 16 -1 (-2000 5050)(-2300 5050);
WIRE 16 -1 (-2300 5100)(-2300 5050);
WIRE 16 -1 (-2000 5100)(-2300 5100);
WIRE 16 -1 (-2300 5150)(-2300 5100);
WIRE 16 -1 (-2000 5150)(-2300 5150);
WIRE 16 -1 (-2300 5200)(-2300 5150);
WIRE 16 -1 (-2000 5200)(-2300 5200);
WIRE 16 -1 (-2300 5250)(-2300 5200);
WIRE 16 -1 (-2000 5250)(-2300 5250);
WIRE 16 -1 (-2300 5300)(-2300 5250);
WIRE 16 -1 (-2000 5300)(-2300 5300);
WIRE 16 -1 (-2300 5350)(-2300 5300);
WIRE 16 -1 (-2000 5350)(-2300 5350);
WIRE 16 -1 (-2300 5400)(-2300 5350);
WIRE 16 -1 (-2000 5400)(-2300 5400);
WIRE 16 -1 (-2300 5450)(-2300 5400);
WIRE 16 -1 (-2000 5450)(-2300 5450);
WIRE 16 -1 (-2300 5500)(-2300 5450);
WIRE 16 -1 (-2000 5500)(-2300 5500);
WIRE 16 -1 (-2300 5550)(-2300 5500);
WIRE 16 -1 (-2000 5550)(-2300 5550);
WIRE 16 -1 (-7675 3125)(-7775 3125);
FORCEPROP 2 LAST SIG_NAME I3C_SPD_DDRC_CPU0_SCL
J 0
(-8135 3075);
DISPLAY 0.361702 (-8135 3075);
FORCEPROP 2 LASTPROP $XRERR UNIQUE?
J 0
(-8375 3075);
DISPLAY 0.638298 (-8375 3075);
PAINT MONO (-8375 3075);
DISPLAY INVISIBLE (-8375 3075);
WIRE 16 -1 (-7775 3125)(-7775 2950);
WIRE 16 -1 (-7775 2950)(-7850 2950);
WIRE 16 -1 (-8350 2475)(-8350 2875);
WIRE 16 -1 (-8350 2475)(-8550 2475);
WIRE 16 -1 (-7675 2875)(-8350 2875);
FORCEPROP 2 LAST SIG_NAME PWRGD_CHC_CPU0_DIMM
J 0
(-8275 2885);
DISPLAY 0.489362 (-8275 2885);
FORCEPROP 2 LASTPROP $XRERR UNIQUE?
J 0
(-8515 2885);
DISPLAY 0.638298 (-8515 2885);
PAINT MONO (-8515 2885);
DISPLAY INVISIBLE (-8515 2885);
WIRE 16 -1 (-8550 2525)(-8550 2475);
WIRE 16 -1 (-8550 2475)(-8575 2475);
WIRE 16 -1 (-9125 2475)(-8775 2475);
FORCEPROP 2 LAST SIG_NAME PWRGD_CHAF_CPU0
J 0
(-9135 2485);
DISPLAY 0.489362 (-9135 2485);
WIRE 16 -1 (-7675 2325)(-8475 2325);
FORCEPROP 2 LAST SIG_NAME M_C_CPU0_SA_RSP<0>
J 0
(-8475 2335);
DISPLAY 0.489362 (-8475 2335);
WIRE 16 -1 (-7675 2275)(-8475 2275);
FORCEPROP 2 LAST SIG_NAME M_C_CPU0_SB_RSP<0>
J 0
(-8475 2285);
DISPLAY 0.489362 (-8475 2285);
WIRE 16 -1 (-6275 2525)(-6475 2525);
WIRE 16 -1 (-6275 4225)(-6475 4225);
WIRE 16 -1 (-6625 1750)(-6625 1675);
WIRE 16 -1 (-6625 1750)(-7350 1750);
FORCEPROP 2 LAST SIG_NAME PD_CHC_CPU0_DIMM_SAA
J 0
(-7335 1760);
DISPLAY 0.489362 (-7335 1760);
WIRE 16 -1 (-3925 3900)(-3775 3900);
WIRE 16 -1 (-3925 3850)(-3575 3850);
WIRE 16 -1 (-3925 4950)(-3775 4950);
WIRE 16 -1 (-3925 4900)(-3575 4900);
WIRE 16 -1 (-3775 4850)(-3925 4850);
WIRE 16 -1 (-3925 4800)(-3575 4800);
WIRE 16 -1 (-3925 3650)(-3575 3650);
WIRE 16 -1 (-3775 4750)(-3925 4750);
WIRE 16 -1 (-3775 3600)(-3925 3600);
WIRE 16 -1 (-3925 3550)(-3575 3550);
WIRE 16 -1 (-3925 4600)(-3575 4600);
WIRE 16 -1 (-3925 3500)(-3775 3500);
WIRE 16 -1 (-3925 3450)(-3575 3450);
WIRE 16 -1 (-3925 4550)(-3775 4550);
WIRE 16 -1 (-3925 4500)(-3575 4500);
WIRE 16 -1 (-3775 3400)(-3925 3400);
WIRE 16 -1 (-3925 3350)(-3575 3350);
WIRE 16 -1 (-3775 4450)(-3925 4450);
WIRE 16 -1 (-3925 4400)(-3575 4400);
WIRE 16 -1 (-3775 3300)(-3925 3300);
WIRE 16 -1 (-3925 3250)(-3575 3250);
WIRE 16 -1 (-3775 4350)(-3925 4350);
WIRE 16 -1 (-3925 4300)(-3575 4300);
WIRE 16 -1 (-3775 3200)(-3925 3200);
WIRE 16 -1 (-3925 3150)(-3575 3150);
WIRE 16 -1 (-3775 4250)(-3925 4250);
WIRE 16 -1 (-3925 4200)(-3575 4200);
WIRE 16 -1 (-3925 3100)(-3775 3100);
WIRE 16 -1 (-3925 3050)(-3575 3050);
WIRE 16 -1 (-3925 4150)(-3775 4150);
WIRE 16 -1 (-3925 4100)(-3575 4100);
WIRE 16 -1 (-3775 3000)(-3925 3000);
WIRE 16 -1 (-3925 2950)(-3575 2950);
WIRE 16 -1 (-3775 4050)(-3925 4050);
WIRE 16 -1 (-3925 4000)(-3575 4000);
WIRE 16 -1 (-3775 3700)(-3925 3700);
WIRE 16 -1 (-3925 3750)(-3575 3750);
WIRE 16 -1 (-3775 3800)(-3925 3800);
WIRE 16 -1 (-3775 4650)(-3925 4650);
WIRE 16 -1 (-3925 4700)(-3575 4700);
WIRE 16 -1 (-6275 5175)(-6475 5175);
WIRE 16 -1 (-6275 5225)(-6475 5225);
WIRE 16 -1 (-6275 5275)(-6475 5275);
WIRE 16 -1 (-6475 5325)(-6275 5325);
WIRE 16 -1 (-6275 5375)(-6475 5375);
WIRE 16 -1 (-6475 5525)(-6275 5525);
WIRE 16 -1 (-6275 5575)(-6475 5575);
WIRE 16 -1 (-7675 4875)(-8475 4875);
FORCEPROP 2 LAST SIG_NAME M_C_CPU0_SB_PAR
J 0
(-8475 4885);
DISPLAY 0.489362 (-8475 4885);
WIRE 16 -1 (-7675 4925)(-8475 4925);
FORCEPROP 2 LAST SIG_NAME M_C_CPU0_SA_PAR
J 0
(-8475 4935);
DISPLAY 0.489362 (-8475 4935);
WIRE 16 -1 (-6275 2575)(-6475 2575);
WIRE 16 -1 (-6275 2625)(-6475 2625);
WIRE 16 -1 (-6475 2675)(-6275 2675);
WIRE 16 -1 (-6275 2725)(-6475 2725);
WIRE 16 -1 (-6275 2775)(-6475 2775);
WIRE 16 -1 (-6275 2825)(-6475 2825);
WIRE 16 -1 (-6475 2875)(-6275 2875);
WIRE 16 -1 (-6275 2925)(-6475 2925);
WIRE 16 -1 (-6275 2975)(-6475 2975);
WIRE 16 -1 (-6275 3025)(-6475 3025);
WIRE 16 -1 (-6475 3075)(-6275 3075);
WIRE 16 -1 (-6275 3125)(-6475 3125);
WIRE 16 -1 (-6275 3175)(-6475 3175);
WIRE 16 -1 (-6275 3225)(-6475 3225);
WIRE 16 -1 (-6475 3275)(-6275 3275);
WIRE 16 -1 (-6275 3325)(-6475 3325);
WIRE 16 -1 (-6275 3375)(-6475 3375);
WIRE 16 -1 (-6275 3425)(-6475 3425);
WIRE 16 -1 (-6475 3475)(-6275 3475);
WIRE 16 -1 (-6275 3525)(-6475 3525);
WIRE 16 -1 (-6275 3575)(-6475 3575);
WIRE 16 -1 (-6275 3625)(-6475 3625);
WIRE 16 -1 (-6475 3675)(-6275 3675);
WIRE 16 -1 (-6275 3725)(-6475 3725);
WIRE 16 -1 (-6275 3775)(-6475 3775);
WIRE 16 -1 (-6275 3825)(-6475 3825);
WIRE 16 -1 (-6475 3875)(-6275 3875);
WIRE 16 -1 (-6275 3925)(-6475 3925);
WIRE 16 -1 (-6275 3975)(-6475 3975);
WIRE 16 -1 (-6275 4025)(-6475 4025);
WIRE 16 -1 (-6475 4075)(-6275 4075);
WIRE 16 -1 (-6275 4175)(-6475 4175);
WIRE 16 -1 (-6275 4275)(-6475 4275);
WIRE 16 -1 (-6475 4325)(-6275 4325);
WIRE 16 -1 (-6275 4375)(-6475 4375);
WIRE 16 -1 (-6275 4425)(-6475 4425);
WIRE 16 -1 (-6275 4475)(-6475 4475);
WIRE 16 -1 (-6475 4525)(-6275 4525);
WIRE 16 -1 (-6275 4575)(-6475 4575);
WIRE 16 -1 (-6275 4625)(-6475 4625);
WIRE 16 -1 (-6275 4675)(-6475 4675);
WIRE 16 -1 (-6475 4725)(-6275 4725);
WIRE 16 -1 (-6275 4775)(-6475 4775);
WIRE 16 -1 (-6275 4825)(-6475 4825);
WIRE 16 -1 (-6275 4875)(-6475 4875);
WIRE 16 -1 (-6475 4925)(-6275 4925);
WIRE 16 -1 (-6275 4975)(-6475 4975);
WIRE 16 -1 (-6275 5025)(-6475 5025);
WIRE 16 -1 (-6275 5075)(-6475 5075);
WIRE 16 -1 (-6475 5125)(-6275 5125);
WIRE 16 -1 (-6275 5425)(-6475 5425);
WIRE 16 -1 (-6275 5475)(-6475 5475);
WIRE 16 -1 (-6275 5625)(-6475 5625);
WIRE 16 -1 (-6275 5675)(-6475 5675);
WIRE 16 -1 (-7675 4625)(-8475 4625);
FORCEPROP 2 LAST SIG_NAME M_C_CPU0_SB_CS_N<1>
J 0
(-8475 4635);
DISPLAY 0.489362 (-8475 4635);
WIRE 16 -1 (-7675 4775)(-8475 4775);
FORCEPROP 2 LAST SIG_NAME M_C_CPU0_SA_CS_N<1>
J 0
(-8475 4785);
DISPLAY 0.489362 (-8475 4785);
WIRE 16 -1 (-7675 4575)(-8475 4575);
FORCEPROP 2 LAST SIG_NAME M_C_CPU0_SB_CS_N<0>
J 0
(-8475 4585);
DISPLAY 0.489362 (-8475 4585);
WIRE 16 -1 (-7675 4725)(-8475 4725);
FORCEPROP 2 LAST SIG_NAME M_C_CPU0_SA_CS_N<0>
J 0
(-8475 4735);
DISPLAY 0.489362 (-8475 4735);
WIRE 16 -1 (-7675 4475)(-8475 4475);
FORCEPROP 2 LAST SIG_NAME M_C_CPU0_CLK_DP<0>
J 0
(-8475 4485);
DISPLAY 0.489362 (-8475 4485);
WIRE 16 -1 (-7675 4425)(-8475 4425);
FORCEPROP 2 LAST SIG_NAME M_C_CPU0_CLK_DN<0>
J 0
(-8475 4435);
DISPLAY 0.489362 (-8475 4435);
WIRE 16 -1 (-7675 3525)(-7875 3525);
WIRE 16 -1 (-7675 3575)(-7875 3575);
WIRE 16 -1 (-7675 3625)(-7875 3625);
WIRE 16 -1 (-7675 3675)(-7875 3675);
WIRE 16 -1 (-7675 3725)(-7875 3725);
WIRE 16 -1 (-7675 3775)(-7875 3775);
WIRE 16 -1 (-7675 3825)(-7875 3825);
WIRE 16 -1 (-7675 3975)(-7875 3975);
WIRE 16 -1 (-7675 4075)(-7875 4075);
WIRE 16 -1 (-7675 4125)(-7875 4125);
WIRE 16 -1 (-7675 4225)(-7875 4225);
WIRE 16 -1 (-7675 4275)(-7875 4275);
WIRE 16 -1 (-7675 5325)(-7875 5325);
WIRE 16 -1 (-7675 5725)(-7875 5725);
WIRE 16 -1 (-7675 5275)(-7875 5275);
WIRE 16 -1 (-7675 5675)(-7875 5675);
WIRE 16 -1 (-7675 5225)(-7875 5225);
WIRE 16 -1 (-7675 5625)(-7875 5625);
WIRE 16 -1 (-7675 5175)(-7875 5175);
WIRE 16 -1 (-7675 5575)(-7875 5575);
WIRE 16 -1 (-7675 5125)(-7875 5125);
WIRE 16 -1 (-7675 5525)(-7875 5525);
WIRE 16 -1 (-7675 5075)(-7875 5075);
WIRE 16 -1 (-7675 5475)(-7875 5475);
WIRE 16 -1 (-7675 5025)(-7875 5025);
WIRE 16 -1 (-7675 5425)(-7875 5425);
WIRE 16 -1 (-7675 3875)(-7875 3875);
WIRE 16 -1 (-7675 4025)(-7875 4025);
WIRE 16 -1 (-7675 4175)(-7875 4175);
WIRE 16 -1 (-7675 4325)(-7875 4325);
WIRE 16 -1 (-6475 5725)(-6275 5725);
WIRE 16 -1 (-7675 3175)(-8175 3175);
FORCEPROP 2 LAST SIG_NAME I3C_SPD_DDRC_CPU0_SDA
J 0
(-8085 3185);
DISPLAY 0.361702 (-8085 3185);
FORCEPROP 2 LASTPROP $XRERR UNIQUE?
J 0
(-8325 3185);
DISPLAY 0.638298 (-8325 3185);
PAINT MONO (-8325 3185);
DISPLAY INVISIBLE (-8325 3185);
WIRE 16 -1 (-7675 3225)(-8475 3225);
FORCEPROP 2 LAST SIG_NAME PD_CHC_CPU0_DIMM_SAA
J 0
(-8475 3235);
DISPLAY 0.489362 (-8475 3235);
WIRE 16 -1 (-8800 3275)(-7675 3275);
WIRE 16 -1 (-8800 3700)(-8800 3275);
WIRE 16 -1 (-8800 3725)(-8800 3700);
WIRE 16 -1 (-8925 3700)(-8800 3700);
WIRE 16 -1 (-8925 3625)(-8925 3700);
DOT 1 (-2425 6350);
DOT 1 (-3000 6350);
DOT 1 (-3000 5925);
DOT 1 (-8550 2475);
DOT 1 (-2300 5700);
DOT 1 (-500 5600);
DOT 1 (-500 5650);
DOT 1 (-500 5550);
DOT 1 (-500 5200);
DOT 1 (-500 5250);
DOT 1 (-500 5300);
DOT 1 (-500 5100);
DOT 1 (-500 5150);
DOT 1 (-500 4950);
DOT 1 (-500 5000);
DOT 1 (-500 5050);
DOT 1 (-500 4850);
DOT 1 (-500 4900);
DOT 1 (-500 4700);
DOT 1 (-500 4750);
DOT 1 (-500 4800);
DOT 1 (-500 4600);
DOT 1 (-500 4650);
DOT 1 (-2300 5500);
DOT 1 (-2300 5450);
DOT 1 (-2300 5400);
DOT 1 (-2300 5350);
DOT 1 (-2300 5250);
DOT 1 (-2300 5100);
DOT 1 (-2300 5150);
DOT 1 (-2300 4950);
DOT 1 (-2300 5000);
DOT 1 (-2300 5050);
DOT 1 (-2300 4900);
DOT 1 (-2300 4700);
DOT 1 (-2300 4750);
DOT 1 (-2300 4800);
DOT 1 (-2300 4600);
DOT 1 (-2300 4650);
DOT 1 (-500 4550);
DOT 1 (-2300 4550);
DOT 1 (-500 4500);
DOT 1 (-500 4450);
DOT 1 (-500 4350);
DOT 1 (-500 4400);
DOT 1 (-500 4300);
DOT 1 (-500 4250);
DOT 1 (-500 4200);
DOT 1 (-500 4100);
DOT 1 (-500 4050);
DOT 1 (-500 4150);
DOT 1 (-500 4000);
DOT 1 (-500 3950);
DOT 1 (-500 3800);
DOT 1 (-500 3850);
DOT 1 (-500 3900);
DOT 1 (-500 3750);
DOT 1 (-500 3700);
DOT 1 (-500 3600);
DOT 1 (-500 3550);
DOT 1 (-500 3650);
DOT 1 (-500 3450);
DOT 1 (-500 3500);
DOT 1 (-500 3400);
DOT 1 (-500 3350);
DOT 1 (-500 3300);
DOT 1 (-500 3200);
DOT 1 (-500 3250);
DOT 1 (-500 3150);
DOT 1 (-500 3050);
DOT 1 (-500 3100);
DOT 1 (-500 2900);
DOT 1 (-500 2950);
DOT 1 (-500 3000);
DOT 1 (-500 2850);
DOT 1 (-500 2800);
DOT 1 (-500 2650);
DOT 1 (-500 2700);
DOT 1 (-500 2750);
DOT 1 (-500 2550);
DOT 1 (-500 2600);
DOT 1 (-500 2450);
DOT 1 (-500 2400);
DOT 1 (-500 2350);
DOT 1 (-2300 4500);
DOT 1 (-2300 4450);
DOT 1 (-2300 4350);
DOT 1 (-2300 4400);
DOT 1 (-2300 4300);
DOT 1 (-2300 4250);
DOT 1 (-2300 4200);
DOT 1 (-2300 4100);
DOT 1 (-2300 4050);
DOT 1 (-2300 4150);
DOT 1 (-2300 4000);
DOT 1 (-2300 3950);
DOT 1 (-2300 3800);
DOT 1 (-2300 3850);
DOT 1 (-2300 3900);
DOT 1 (-2300 3750);
DOT 1 (-2300 3700);
DOT 1 (-2300 3650);
DOT 1 (-2300 3550);
DOT 1 (-2300 3600);
DOT 1 (-2300 3450);
DOT 1 (-2300 3500);
DOT 1 (-2300 3350);
DOT 1 (-2300 3300);
DOT 1 (-2300 3200);
DOT 1 (-2300 3250);
DOT 1 (-2300 3150);
DOT 1 (-2300 3050);
DOT 1 (-2300 3100);
DOT 1 (-2300 2900);
DOT 1 (-2300 2950);
DOT 1 (-2300 3000);
DOT 1 (-2300 2850);
DOT 1 (-2300 2800);
DOT 1 (-2300 2650);
DOT 1 (-2300 2700);
DOT 1 (-2300 2750);
DOT 1 (-2300 2550);
DOT 1 (-2300 2600);
DOT 1 (-2300 2500);
DOT 1 (-2300 2450);
DOT 1 (-2300 3400);
DOT 1 (-500 5500);
DOT 1 (-500 5450);
DOT 1 (-500 5400);
DOT 1 (-500 5350);
DOT 1 (-2300 4850);
DOT 1 (-2300 5200);
DOT 1 (-2300 5300);
DOT 1 (-2300 5650);
DOT 1 (-8800 3700);
QUIT
